(kicad_sch
	(version 20250114)
	(generator "eeschema")
	(generator_version "9.0")
	(paper "A3")
	(title_block
		(title "Thunderbolt to 10GbE adapter")
		(date "2026-04-23")
		(rev "1.1.0")
		(company "Antmicro Ltd")
		(comment 1 "www.antmicro.com")
	)
	(rectangle
		(start 250.444 26.67)
		(end 272.034 33.02)
		(stroke
			(width 0)
			(type default)
		)
		(fill
			(type none)
		)
	)
	(text "Close switch to\nenable debug mode"
		(exclude_from_sim no)
		(at 251.46 31.75 0)
		(effects
			(font
				(size 1.27 1.27)
			)
			(justify left bottom)
		)
	)
	(text "X710-AT2 Reserved Pins"
		(exclude_from_sim no)
		(at 215.9 25.4 0)
		(effects
			(font
				(size 2.54 2.54)
				(thickness 0.508)
				(bold yes)
			)
		)
	)
	(junction
		(at 193.04 196.85)
		(diameter 0)
		(color 0 0 0 0)
	)
	(junction
		(at 193.04 217.17)
		(diameter 0)
		(color 0 0 0 0)
	)
	(junction
		(at 276.86 49.53)
		(diameter 0)
		(color 0 0 0 0)
	)
	(junction
		(at 193.04 214.63)
		(diameter 0)
		(color 0 0 0 0)
	)
	(junction
		(at 193.04 219.71)
		(diameter 0)
		(color 0 0 0 0)
	)
	(junction
		(at 193.04 189.23)
		(diameter 0)
		(color 0 0 0 0)
	)
	(junction
		(at 269.24 52.07)
		(diameter 0)
		(color 0 0 0 0)
	)
	(junction
		(at 173.99 168.91)
		(diameter 0)
		(color 0 0 0 0)
	)
	(junction
		(at 193.04 212.09)
		(diameter 0)
		(color 0 0 0 0)
	)
	(junction
		(at 193.04 207.01)
		(diameter 0)
		(color 0 0 0 0)
	)
	(junction
		(at 193.04 199.39)
		(diameter 0)
		(color 0 0 0 0)
	)
	(junction
		(at 241.3 232.41)
		(diameter 0)
		(color 0 0 0 0)
	)
	(junction
		(at 241.3 229.87)
		(diameter 0)
		(color 0 0 0 0)
	)
	(junction
		(at 193.04 201.93)
		(diameter 0)
		(color 0 0 0 0)
	)
	(junction
		(at 261.62 54.61)
		(diameter 0)
		(color 0 0 0 0)
	)
	(junction
		(at 276.86 39.37)
		(diameter 0)
		(color 0 0 0 0)
	)
	(junction
		(at 269.24 39.37)
		(diameter 0)
		(color 0 0 0 0)
	)
	(junction
		(at 193.04 186.69)
		(diameter 0)
		(color 0 0 0 0)
	)
	(junction
		(at 193.04 209.55)
		(diameter 0)
		(color 0 0 0 0)
	)
	(junction
		(at 193.04 194.31)
		(diameter 0)
		(color 0 0 0 0)
	)
	(junction
		(at 193.04 204.47)
		(diameter 0)
		(color 0 0 0 0)
	)
	(junction
		(at 193.04 191.77)
		(diameter 0)
		(color 0 0 0 0)
	)
	(no_connect
		(at 238.76 212.09)
	)
	(no_connect
		(at 238.76 135.89)
	)
	(no_connect
		(at 238.76 237.49)
	)
	(no_connect
		(at 195.58 88.9)
	)
	(no_connect
		(at 195.58 81.28)
	)
	(no_connect
		(at 238.76 120.65)
	)
	(no_connect
		(at 238.76 110.49)
	)
	(no_connect
		(at 238.76 62.23)
	)
	(no_connect
		(at 238.76 214.63)
	)
	(no_connect
		(at 238.76 118.11)
	)
	(no_connect
		(at 238.76 97.79)
	)
	(no_connect
		(at 195.58 86.36)
	)
	(no_connect
		(at 238.76 67.31)
	)
	(no_connect
		(at 195.58 245.11)
	)
	(no_connect
		(at 238.76 77.47)
	)
	(no_connect
		(at 195.58 247.65)
	)
	(no_connect
		(at 195.58 229.87)
	)
	(no_connect
		(at 238.76 125.73)
	)
	(no_connect
		(at 238.76 105.41)
	)
	(no_connect
		(at 195.58 227.33)
	)
	(no_connect
		(at 238.76 140.97)
	)
	(no_connect
		(at 238.76 69.85)
	)
	(no_connect
		(at 195.58 240.03)
	)
	(no_connect
		(at 238.76 113.03)
	)
	(no_connect
		(at 238.76 123.19)
	)
	(no_connect
		(at 238.76 92.71)
	)
	(no_connect
		(at 238.76 59.69)
	)
	(no_connect
		(at 238.76 85.09)
	)
	(no_connect
		(at 238.76 95.25)
	)
	(no_connect
		(at 238.76 64.77)
	)
	(no_connect
		(at 195.58 237.49)
	)
	(no_connect
		(at 195.58 224.79)
	)
	(no_connect
		(at 238.76 196.85)
	)
	(no_connect
		(at 238.76 219.71)
	)
	(no_connect
		(at 238.76 87.63)
	)
	(no_connect
		(at 238.76 207.01)
	)
	(no_connect
		(at 238.76 82.55)
	)
	(no_connect
		(at 238.76 74.93)
	)
	(no_connect
		(at 238.76 199.39)
	)
	(no_connect
		(at 238.76 72.39)
	)
	(no_connect
		(at 238.76 181.61)
	)
	(no_connect
		(at 238.76 179.07)
	)
	(no_connect
		(at 238.76 184.15)
	)
	(no_connect
		(at 238.76 191.77)
	)
	(no_connect
		(at 195.58 83.82)
	)
	(no_connect
		(at 238.76 100.33)
	)
	(no_connect
		(at 195.58 232.41)
	)
	(no_connect
		(at 238.76 194.31)
	)
	(no_connect
		(at 238.76 209.55)
	)
	(no_connect
		(at 238.76 128.27)
	)
	(no_connect
		(at 238.76 133.35)
	)
	(no_connect
		(at 238.76 115.57)
	)
	(no_connect
		(at 238.76 102.87)
	)
	(no_connect
		(at 238.76 234.95)
	)
	(no_connect
		(at 238.76 201.93)
	)
	(no_connect
		(at 238.76 130.81)
	)
	(no_connect
		(at 238.76 189.23)
	)
	(no_connect
		(at 238.76 80.01)
	)
	(no_connect
		(at 238.76 90.17)
	)
	(no_connect
		(at 238.76 107.95)
	)
	(no_connect
		(at 238.76 204.47)
	)
	(no_connect
		(at 238.76 138.43)
	)
	(no_connect
		(at 238.76 217.17)
	)
	(no_connect
		(at 238.76 186.69)
	)
	(wire
		(pts
			(xy 153.67 64.77) (xy 195.58 64.77)
		)
		(stroke
			(width 0)
			(type default)
		)
	)
	(wire
		(pts
			(xy 193.04 219.71) (xy 195.58 219.71)
		)
		(stroke
			(width 0)
			(type default)
		)
	)
	(wire
		(pts
			(xy 127 76.2) (xy 127 54.61)
		)
		(stroke
			(width 0)
			(type default)
		)
	)
	(wire
		(pts
			(xy 180.34 73.66) (xy 195.58 73.66)
		)
		(stroke
			(width 0)
			(type default)
		)
	)
	(wire
		(pts
			(xy 261.62 39.37) (xy 269.24 39.37)
		)
		(stroke
			(width 0)
			(type default)
		)
	)
	(wire
		(pts
			(xy 269.24 52.07) (xy 269.24 57.15)
		)
		(stroke
			(width 0)
			(type default)
		)
	)
	(wire
		(pts
			(xy 195.58 186.69) (xy 193.04 186.69)
		)
		(stroke
			(width 0)
			(type default)
		)
	)
	(wire
		(pts
			(xy 276.86 36.83) (xy 276.86 39.37)
		)
		(stroke
			(width 0)
			(type default)
		)
	)
	(wire
		(pts
			(xy 193.04 219.71) (xy 193.04 250.19)
		)
		(stroke
			(width 0)
			(type default)
		)
	)
	(wire
		(pts
			(xy 173.99 168.91) (xy 173.99 171.45)
		)
		(stroke
			(width 0)
			(type default)
		)
	)
	(wire
		(pts
			(xy 193.04 189.23) (xy 193.04 191.77)
		)
		(stroke
			(width 0)
			(type default)
		)
	)
	(wire
		(pts
			(xy 195.58 212.09) (xy 193.04 212.09)
		)
		(stroke
			(width 0)
			(type default)
		)
	)
	(wire
		(pts
			(xy 241.3 229.87) (xy 241.3 232.41)
		)
		(stroke
			(width 0)
			(type default)
		)
	)
	(wire
		(pts
			(xy 153.67 81.28) (xy 153.67 83.82)
		)
		(stroke
			(width 0)
			(type default)
		)
	)
	(wire
		(pts
			(xy 195.58 189.23) (xy 193.04 189.23)
		)
		(stroke
			(width 0)
			(type default)
		)
	)
	(wire
		(pts
			(xy 261.62 54.61) (xy 261.62 57.15)
		)
		(stroke
			(width 0)
			(type default)
		)
	)
	(wire
		(pts
			(xy 193.04 184.15) (xy 193.04 186.69)
		)
		(stroke
			(width 0)
			(type default)
		)
	)
	(wire
		(pts
			(xy 269.24 39.37) (xy 276.86 39.37)
		)
		(stroke
			(width 0)
			(type default)
		)
	)
	(wire
		(pts
			(xy 166.37 168.91) (xy 166.37 171.45)
		)
		(stroke
			(width 0)
			(type default)
		)
	)
	(wire
		(pts
			(xy 238.76 52.07) (xy 269.24 52.07)
		)
		(stroke
			(width 0)
			(type default)
		)
	)
	(wire
		(pts
			(xy 276.86 46.99) (xy 276.86 49.53)
		)
		(stroke
			(width 0)
			(type default)
		)
	)
	(wire
		(pts
			(xy 193.04 201.93) (xy 193.04 204.47)
		)
		(stroke
			(width 0)
			(type default)
		)
	)
	(wire
		(pts
			(xy 173.99 166.37) (xy 173.99 168.91)
		)
		(stroke
			(width 0)
			(type default)
		)
	)
	(wire
		(pts
			(xy 269.24 62.23) (xy 269.24 64.77)
		)
		(stroke
			(width 0)
			(type default)
		)
	)
	(wire
		(pts
			(xy 171.45 81.28) (xy 171.45 83.82)
		)
		(stroke
			(width 0)
			(type default)
		)
	)
	(wire
		(pts
			(xy 193.04 214.63) (xy 193.04 217.17)
		)
		(stroke
			(width 0)
			(type default)
		)
	)
	(wire
		(pts
			(xy 193.04 186.69) (xy 193.04 189.23)
		)
		(stroke
			(width 0)
			(type default)
		)
	)
	(wire
		(pts
			(xy 173.99 176.53) (xy 173.99 179.07)
		)
		(stroke
			(width 0)
			(type default)
		)
	)
	(wire
		(pts
			(xy 276.86 62.23) (xy 276.86 64.77)
		)
		(stroke
			(width 0)
			(type default)
		)
	)
	(wire
		(pts
			(xy 193.04 209.55) (xy 193.04 212.09)
		)
		(stroke
			(width 0)
			(type default)
		)
	)
	(wire
		(pts
			(xy 238.76 232.41) (xy 241.3 232.41)
		)
		(stroke
			(width 0)
			(type default)
		)
	)
	(wire
		(pts
			(xy 166.37 176.53) (xy 166.37 181.61)
		)
		(stroke
			(width 0)
			(type default)
		)
	)
	(wire
		(pts
			(xy 193.04 207.01) (xy 193.04 209.55)
		)
		(stroke
			(width 0)
			(type default)
		)
	)
	(wire
		(pts
			(xy 135.89 57.15) (xy 195.58 57.15)
		)
		(stroke
			(width 0)
			(type default)
		)
	)
	(wire
		(pts
			(xy 193.04 212.09) (xy 193.04 214.63)
		)
		(stroke
			(width 0)
			(type default)
		)
	)
	(wire
		(pts
			(xy 193.04 196.85) (xy 193.04 199.39)
		)
		(stroke
			(width 0)
			(type default)
		)
	)
	(wire
		(pts
			(xy 193.04 204.47) (xy 193.04 207.01)
		)
		(stroke
			(width 0)
			(type default)
		)
	)
	(wire
		(pts
			(xy 144.78 81.28) (xy 144.78 83.82)
		)
		(stroke
			(width 0)
			(type default)
		)
	)
	(wire
		(pts
			(xy 162.56 81.28) (xy 162.56 83.82)
		)
		(stroke
			(width 0)
			(type default)
		)
	)
	(wire
		(pts
			(xy 144.78 76.2) (xy 144.78 62.23)
		)
		(stroke
			(width 0)
			(type default)
		)
	)
	(wire
		(pts
			(xy 238.76 54.61) (xy 261.62 54.61)
		)
		(stroke
			(width 0)
			(type default)
		)
	)
	(wire
		(pts
			(xy 195.58 196.85) (xy 193.04 196.85)
		)
		(stroke
			(width 0)
			(type default)
		)
	)
	(wire
		(pts
			(xy 173.99 179.07) (xy 195.58 179.07)
		)
		(stroke
			(width 0)
			(type default)
		)
	)
	(wire
		(pts
			(xy 195.58 191.77) (xy 193.04 191.77)
		)
		(stroke
			(width 0)
			(type default)
		)
	)
	(wire
		(pts
			(xy 127 81.28) (xy 127 83.82)
		)
		(stroke
			(width 0)
			(type default)
		)
	)
	(wire
		(pts
			(xy 166.37 181.61) (xy 195.58 181.61)
		)
		(stroke
			(width 0)
			(type default)
		)
	)
	(wire
		(pts
			(xy 241.3 224.79) (xy 241.3 229.87)
		)
		(stroke
			(width 0)
			(type default)
		)
	)
	(wire
		(pts
			(xy 180.34 81.28) (xy 180.34 83.82)
		)
		(stroke
			(width 0)
			(type default)
		)
	)
	(wire
		(pts
			(xy 162.56 67.31) (xy 195.58 67.31)
		)
		(stroke
			(width 0)
			(type default)
		)
	)
	(wire
		(pts
			(xy 276.86 41.91) (xy 276.86 39.37)
		)
		(stroke
			(width 0)
			(type default)
		)
	)
	(wire
		(pts
			(xy 135.89 81.28) (xy 135.89 83.82)
		)
		(stroke
			(width 0)
			(type default)
		)
	)
	(wire
		(pts
			(xy 166.37 168.91) (xy 173.99 168.91)
		)
		(stroke
			(width 0)
			(type default)
		)
	)
	(wire
		(pts
			(xy 162.56 76.2) (xy 162.56 67.31)
		)
		(stroke
			(width 0)
			(type default)
		)
	)
	(wire
		(pts
			(xy 195.58 199.39) (xy 193.04 199.39)
		)
		(stroke
			(width 0)
			(type default)
		)
	)
	(wire
		(pts
			(xy 276.86 21.59) (xy 276.86 24.13)
		)
		(stroke
			(width 0)
			(type default)
		)
	)
	(wire
		(pts
			(xy 193.04 191.77) (xy 193.04 194.31)
		)
		(stroke
			(width 0)
			(type default)
		)
	)
	(wire
		(pts
			(xy 144.78 62.23) (xy 195.58 62.23)
		)
		(stroke
			(width 0)
			(type default)
		)
	)
	(wire
		(pts
			(xy 241.3 232.41) (xy 241.3 250.19)
		)
		(stroke
			(width 0)
			(type default)
		)
	)
	(wire
		(pts
			(xy 195.58 214.63) (xy 193.04 214.63)
		)
		(stroke
			(width 0)
			(type default)
		)
	)
	(wire
		(pts
			(xy 195.58 209.55) (xy 193.04 209.55)
		)
		(stroke
			(width 0)
			(type default)
		)
	)
	(wire
		(pts
			(xy 153.67 76.2) (xy 153.67 64.77)
		)
		(stroke
			(width 0)
			(type default)
		)
	)
	(wire
		(pts
			(xy 269.24 41.91) (xy 269.24 39.37)
		)
		(stroke
			(width 0)
			(type default)
		)
	)
	(wire
		(pts
			(xy 195.58 184.15) (xy 193.04 184.15)
		)
		(stroke
			(width 0)
			(type default)
		)
	)
	(wire
		(pts
			(xy 238.76 224.79) (xy 241.3 224.79)
		)
		(stroke
			(width 0)
			(type default)
		)
	)
	(wire
		(pts
			(xy 171.45 69.85) (xy 195.58 69.85)
		)
		(stroke
			(width 0)
			(type default)
		)
	)
	(wire
		(pts
			(xy 135.89 76.2) (xy 135.89 57.15)
		)
		(stroke
			(width 0)
			(type default)
		)
	)
	(wire
		(pts
			(xy 195.58 204.47) (xy 193.04 204.47)
		)
		(stroke
			(width 0)
			(type default)
		)
	)
	(wire
		(pts
			(xy 261.62 41.91) (xy 261.62 39.37)
		)
		(stroke
			(width 0)
			(type default)
		)
	)
	(wire
		(pts
			(xy 195.58 194.31) (xy 193.04 194.31)
		)
		(stroke
			(width 0)
			(type default)
		)
	)
	(wire
		(pts
			(xy 171.45 76.2) (xy 171.45 69.85)
		)
		(stroke
			(width 0)
			(type default)
		)
	)
	(wire
		(pts
			(xy 193.04 194.31) (xy 193.04 196.85)
		)
		(stroke
			(width 0)
			(type default)
		)
	)
	(wire
		(pts
			(xy 269.24 46.99) (xy 269.24 52.07)
		)
		(stroke
			(width 0)
			(type default)
		)
	)
	(wire
		(pts
			(xy 193.04 217.17) (xy 193.04 219.71)
		)
		(stroke
			(width 0)
			(type default)
		)
	)
	(wire
		(pts
			(xy 261.62 46.99) (xy 261.62 54.61)
		)
		(stroke
			(width 0)
			(type default)
		)
	)
	(wire
		(pts
			(xy 180.34 76.2) (xy 180.34 73.66)
		)
		(stroke
			(width 0)
			(type default)
		)
	)
	(wire
		(pts
			(xy 238.76 229.87) (xy 241.3 229.87)
		)
		(stroke
			(width 0)
			(type default)
		)
	)
	(wire
		(pts
			(xy 195.58 217.17) (xy 193.04 217.17)
		)
		(stroke
			(width 0)
			(type default)
		)
	)
	(wire
		(pts
			(xy 195.58 201.93) (xy 193.04 201.93)
		)
		(stroke
			(width 0)
			(type default)
		)
	)
	(wire
		(pts
			(xy 276.86 49.53) (xy 276.86 57.15)
		)
		(stroke
			(width 0)
			(type default)
		)
	)
	(wire
		(pts
			(xy 195.58 207.01) (xy 193.04 207.01)
		)
		(stroke
			(width 0)
			(type default)
		)
	)
	(wire
		(pts
			(xy 118.11 81.28) (xy 118.11 83.82)
		)
		(stroke
			(width 0)
			(type default)
		)
	)
	(wire
		(pts
			(xy 238.76 49.53) (xy 276.86 49.53)
		)
		(stroke
			(width 0)
			(type default)
		)
	)
	(wire
		(pts
			(xy 127 54.61) (xy 195.58 54.61)
		)
		(stroke
			(width 0)
			(type default)
		)
	)
	(wire
		(pts
			(xy 118.11 49.53) (xy 195.58 49.53)
		)
		(stroke
			(width 0)
			(type default)
		)
	)
	(wire
		(pts
			(xy 193.04 199.39) (xy 193.04 201.93)
		)
		(stroke
			(width 0)
			(type default)
		)
	)
	(wire
		(pts
			(xy 118.11 76.2) (xy 118.11 49.53)
		)
		(stroke
			(width 0)
			(type default)
		)
	)
	(wire
		(pts
			(xy 261.62 62.23) (xy 261.62 64.77)
		)
		(stroke
			(width 0)
			(type default)
		)
	)
	(label "DEBUG_EN"
		(at 261.62 39.37 0)
		(effects
			(font
				(size 1.27 1.27)
			)
			(justify left bottom)
		)
	)
	(label "RSVDN9_VSS"
		(at 193.04 62.23 180)
		(effects
			(font
				(size 1.27 1.27)
			)
			(justify right bottom)
		)
	)
	(label "RSVDP22_VSS"
		(at 193.04 67.31 180)
		(effects
			(font
				(size 1.27 1.27)
			)
			(justify right bottom)
		)
	)
	(label "DEBUG_W7"
		(at 241.3 52.07 0)
		(effects
			(font
				(size 1.27 1.27)
			)
			(justify left bottom)
		)
	)
	(label "RSVDY18_VSS"
		(at 193.04 69.85 180)
		(effects
			(font
				(size 1.27 1.27)
			)
			(justify right bottom)
		)
	)
	(label "RSVDY22_VSS"
		(at 193.04 54.61 180)
		(effects
			(font
				(size 1.27 1.27)
			)
			(justify right bottom)
		)
	)
	(label "DEBUG_Y20"
		(at 241.3 54.61 0)
		(effects
			(font
				(size 1.27 1.27)
			)
			(justify left bottom)
		)
	)
	(label "RSVDW1_VSS"
		(at 193.04 64.77 180)
		(effects
			(font
				(size 1.27 1.27)
			)
			(justify right bottom)
		)
	)
	(label "RSVDE19_1P88V"
		(at 193.04 179.07 180)
		(effects
			(font
				(size 1.27 1.27)
			)
			(justify right bottom)
		)
	)
	(label "RSVDW5_VSS"
		(at 193.04 57.15 180)
		(effects
			(font
				(size 1.27 1.27)
			)
			(justify right bottom)
		)
	)
	(label "RSVDY24_VSS"
		(at 193.04 49.53 180)
		(effects
			(font
				(size 1.27 1.27)
			)
			(justify right bottom)
		)
	)
	(label "DEBUG_Y16"
		(at 241.3 49.53 0)
		(effects
			(font
				(size 1.27 1.27)
			)
			(justify left bottom)
		)
	)
	(label "RSVDD8_1P88V"
		(at 193.04 181.61 180)
		(effects
			(font
				(size 1.27 1.27)
			)
			(justify right bottom)
		)
	)
	(label "RSVDP8_VSS"
		(at 193.04 73.66 180)
		(effects
			(font
				(size 1.27 1.27)
			)
			(justify right bottom)
		)
	)
	(symbol
		(lib_id "antmicroResistors0402:R_1k_0402")
		(at 166.37 176.53 90)
		(unit 1)
		(exclude_from_sim no)
		(in_bom yes)
		(on_board yes)
		(dnp no)
		(property "Reference" "R127"
			(at 167.894 172.72 90)
			(effects
				(font
					(size 1.27 1.27)
					(thickness 0.15)
				)
				(justify right)
			)
		)
		(property "Value" "R_1k_0402"
			(at 179.07 156.21 0)
			(effects
				(font
					(size 1.27 1.27)
					(thickness 0.15)
				)
				(justify left bottom)
				(hide yes)
			)
		)
		(property "Footprint" "antmicro-footprints:R_0402_1005Metric"
			(at 181.61 156.21 0)
			(effects
				(font
					(size 1.27 1.27)
					(thickness 0.15)
				)
				(justify left bottom)
				(hide yes)
			)
		)
		(property "Datasheet" "https://www.bourns.com/docs/product-datasheets/cr.pdf"
			(at 184.15 156.21 0)
			(effects
				(font
					(size 1.27 1.27)
					(thickness 0.15)
				)
				(justify left bottom)
				(hide yes)
			)
		)
		(property "Description" "SMD Chip Resistor, 1 kohm, ± 1%, 63 mW, 0402 [1005 Metric], Thick Film, General Purpose"
			(at 166.37 176.53 0)
			(effects
				(font
					(size 1.27 1.27)
				)
				(hide yes)
			)
		)
		(property "MPN" "CR0402-FX-1001GLF"
			(at 186.69 156.21 0)
			(effects
				(font
					(size 1.27 1.27)
					(thickness 0.15)
				)
				(justify left bottom)
				(hide yes)
			)
		)
		(property "Manufacturer" "Bourns"
			(at 189.23 156.21 0)
			(effects
				(font
					(size 1.27 1.27)
					(thickness 0.15)
				)
				(justify left bottom)
				(hide yes)
			)
		)
		(property "License" "Apache-2.0"
			(at 191.77 156.21 0)
			(effects
				(font
					(size 1.27 1.27)
					(thickness 0.15)
				)
				(justify left bottom)
				(hide yes)
			)
		)
		(property "Author" "Antmicro"
			(at 194.31 156.21 0)
			(effects
				(font
					(size 1.27 1.27)
					(thickness 0.15)
				)
				(justify left bottom)
				(hide yes)
			)
		)
		(property "Val" "1k"
			(at 167.894 175.26 90)
			(effects
				(font
					(size 1.27 1.27)
					(thickness 0.15)
				)
				(justify right)
			)
		)
		(property "Tolerance" "1%"
			(at 176.53 156.21 0)
			(effects
				(font
					(size 1.27 1.27)
				)
				(justify left bottom)
				(hide yes)
			)
		)
		(pin "2"
		)
		(pin "1"
		)
		(instances
			(project "OCuLink to 10GbE adapter"
				(path ""
					(reference "R142")
					(unit 1)
				)
			)
			(project "thunderbolt-to-10gbe-adapter"
				(path ""
					(reference "R127")
					(unit 1)
				)
			)
		)
	)
	(symbol
		(lib_id "antmicroResistors0402:R_100R_0402")
		(at 180.34 81.28 90)
		(unit 1)
		(exclude_from_sim no)
		(in_bom yes)
		(on_board yes)
		(dnp no)
		(property "Reference" "R130"
			(at 181.864 77.47 90)
			(effects
				(font
					(size 1.27 1.27)
					(thickness 0.15)
				)
				(justify right)
			)
		)
		(property "Value" "R_100R_0402"
			(at 193.04 60.96 0)
			(effects
				(font
					(size 1.27 1.27)
					(thickness 0.15)
				)
				(justify left bottom)
				(hide yes)
			)
		)
		(property "Footprint" "antmicro-footprints:R_0402_1005Metric"
			(at 195.58 60.96 0)
			(effects
				(font
					(size 1.27 1.27)
					(thickness 0.15)
				)
				(justify left bottom)
				(hide yes)
			)
		)
		(property "Datasheet" "https://www.bourns.com/docs/product-datasheets/cr.pdf"
			(at 198.12 60.96 0)
			(effects
				(font
					(size 1.27 1.27)
					(thickness 0.15)
				)
				(justify left bottom)
				(hide yes)
			)
		)
		(property "Description" "SMD Chip Resistor, 100 ohm, ± 1%, 62.5 mW, 0402 [1005 Metric], Thick Film, General Purpose"
			(at 180.34 81.28 0)
			(effects
				(font
					(size 1.27 1.27)
				)
				(hide yes)
			)
		)
		(property "MPN" "CR0402-FX-1000GLF"
			(at 200.66 60.96 0)
			(effects
				(font
					(size 1.27 1.27)
					(thickness 0.15)
				)
				(justify left bottom)
				(hide yes)
			)
		)
		(property "Manufacturer" "Bourns"
			(at 203.2 60.96 0)
			(effects
				(font
					(size 1.27 1.27)
					(thickness 0.15)
				)
				(justify left bottom)
				(hide yes)
			)
		)
		(property "License" "Apache-2.0"
			(at 205.74 60.96 0)
			(effects
				(font
					(size 1.27 1.27)
					(thickness 0.15)
				)
				(justify left bottom)
				(hide yes)
			)
		)
		(property "Author" "Antmicro"
			(at 208.28 60.96 0)
			(effects
				(font
					(size 1.27 1.27)
					(thickness 0.15)
				)
				(justify left bottom)
				(hide yes)
			)
		)
		(property "Val" "100R"
			(at 181.864 80.01 90)
			(effects
				(font
					(size 1.27 1.27)
					(thickness 0.15)
				)
				(justify right)
			)
		)
		(property "Tolerance" "1%"
			(at 190.5 60.96 0)
			(effects
				(font
					(size 1.27 1.27)
				)
				(justify left bottom)
				(hide yes)
			)
		)
		(pin "2"
		)
		(pin "1"
		)
		(instances
			(project ""
				(path ""
					(reference "R141")
					(unit 1)
				)
			)
			(project "thunderbolt-to-10gbe-adapter"
				(path ""
					(reference "R130")
					(unit 1)
				)
			)
		)
	)
	(symbol
		(lib_id "antmicroResistors0402:R_1k_0402")
		(at 269.24 46.99 90)
		(unit 1)
		(exclude_from_sim no)
		(in_bom yes)
		(on_board yes)
		(dnp no)
		(property "Reference" "R133"
			(at 270.764 43.18 90)
			(effects
				(font
					(size 1.27 1.27)
					(thickness 0.15)
				)
				(justify right)
			)
		)
		(property "Value" "R_1k_0402"
			(at 281.94 26.67 0)
			(effects
				(font
					(size 1.27 1.27)
					(thickness 0.15)
				)
				(justify left bottom)
				(hide yes)
			)
		)
		(property "Footprint" "antmicro-footprints:R_0402_1005Metric"
			(at 284.48 26.67 0)
			(effects
				(font
					(size 1.27 1.27)
					(thickness 0.15)
				)
				(justify left bottom)
				(hide yes)
			)
		)
		(property "Datasheet" "https://www.bourns.com/docs/product-datasheets/cr.pdf"
			(at 287.02 26.67 0)
			(effects
				(font
					(size 1.27 1.27)
					(thickness 0.15)
				)
				(justify left bottom)
				(hide yes)
			)
		)
		(property "Description" "SMD Chip Resistor, 1 kohm, ± 1%, 63 mW, 0402 [1005 Metric], Thick Film, General Purpose"
			(at 269.24 46.99 0)
			(effects
				(font
					(size 1.27 1.27)
				)
				(hide yes)
			)
		)
		(property "MPN" "CR0402-FX-1001GLF"
			(at 289.56 26.67 0)
			(effects
				(font
					(size 1.27 1.27)
					(thickness 0.15)
				)
				(justify left bottom)
				(hide yes)
			)
		)
		(property "Manufacturer" "Bourns"
			(at 292.1 26.67 0)
			(effects
				(font
					(size 1.27 1.27)
					(thickness 0.15)
				)
				(justify left bottom)
				(hide yes)
			)
		)
		(property "License" "Apache-2.0"
			(at 294.64 26.67 0)
			(effects
				(font
					(size 1.27 1.27)
					(thickness 0.15)
				)
				(justify left bottom)
				(hide yes)
			)
		)
		(property "Author" "Antmicro"
			(at 297.18 26.67 0)
			(effects
				(font
					(size 1.27 1.27)
					(thickness 0.15)
				)
				(justify left bottom)
				(hide yes)
			)
		)
		(property "Val" "1k"
			(at 270.764 45.72 90)
			(effects
				(font
					(size 1.27 1.27)
					(thickness 0.15)
				)
				(justify right)
			)
		)
		(property "Tolerance" "1%"
			(at 279.4 26.67 0)
			(effects
				(font
					(size 1.27 1.27)
				)
				(justify left bottom)
				(hide yes)
			)
		)
		(pin "2"
		)
		(pin "1"
		)
		(instances
			(project "OCuLink to 10GbE adapter"
				(path ""
					(reference "R129")
					(unit 1)
				)
			)
			(project "thunderbolt-to-10gbe-adapter"
				(path ""
					(reference "R133")
					(unit 1)
				)
			)
		)
	)
	(symbol
		(lib_id "antmicropower:GND")
		(at 276.86 64.77 0)
		(unit 1)
		(exclude_from_sim no)
		(in_bom yes)
		(on_board yes)
		(dnp no)
		(property "Reference" "#PWR0371"
			(at 285.75 67.31 0)
			(effects
				(font
					(size 1.27 1.27)
					(thickness 0.15)
				)
				(justify left bottom)
				(hide yes)
			)
		)
		(property "Value" "GND"
			(at 276.86 68.58 0)
			(effects
				(font
					(size 1.27 1.27)
					(thickness 0.15)
				)
			)
		)
		(property "Footprint" ""
			(at 285.75 72.39 0)
			(effects
				(font
					(size 1.27 1.27)
					(thickness 0.15)
				)
				(justify left bottom)
				(hide yes)
			)
		)
		(property "Datasheet" ""
			(at 285.75 77.47 0)
			(effects
				(font
					(size 1.27 1.27)
					(thickness 0.15)
				)
				(justify left bottom)
				(hide yes)
			)
		)
		(property "Description" ""
			(at 276.86 64.77 0)
			(effects
				(font
					(size 1.27 1.27)
				)
				(hide yes)
			)
		)
		(property "Author" "Antmicro"
			(at 285.75 72.39 0)
			(effects
				(font
					(size 1.27 1.27)
					(thickness 0.15)
				)
				(justify left bottom)
				(hide yes)
			)
		)
		(property "License" "Apache-2.0"
			(at 285.75 74.93 0)
			(effects
				(font
					(size 1.27 1.27)
					(thickness 0.15)
				)
				(justify left bottom)
				(hide yes)
			)
		)
		(pin "1"
		)
		(instances
			(project "OCuLink to 10GbE adapter"
				(path ""
					(reference "#PWR0292")
					(unit 1)
				)
			)
			(project "thunderbolt-to-10gbe-adapter"
				(path ""
					(reference "#PWR0371")
					(unit 1)
				)
			)
		)
	)
	(symbol
		(lib_id "antmicroResistors0402:R_100R_0402")
		(at 171.45 81.28 90)
		(unit 1)
		(exclude_from_sim no)
		(in_bom yes)
		(on_board yes)
		(dnp no)
		(property "Reference" "R128"
			(at 172.974 77.47 90)
			(effects
				(font
					(size 1.27 1.27)
					(thickness 0.15)
				)
				(justify right)
			)
		)
		(property "Value" "R_100R_0402"
			(at 184.15 60.96 0)
			(effects
				(font
					(size 1.27 1.27)
					(thickness 0.15)
				)
				(justify left bottom)
				(hide yes)
			)
		)
		(property "Footprint" "antmicro-footprints:R_0402_1005Metric"
			(at 186.69 60.96 0)
			(effects
				(font
					(size 1.27 1.27)
					(thickness 0.15)
				)
				(justify left bottom)
				(hide yes)
			)
		)
		(property "Datasheet" "https://www.bourns.com/docs/product-datasheets/cr.pdf"
			(at 189.23 60.96 0)
			(effects
				(font
					(size 1.27 1.27)
					(thickness 0.15)
				)
				(justify left bottom)
				(hide yes)
			)
		)
		(property "Description" "SMD Chip Resistor, 100 ohm, ± 1%, 62.5 mW, 0402 [1005 Metric], Thick Film, General Purpose"
			(at 171.45 81.28 0)
			(effects
				(font
					(size 1.27 1.27)
				)
				(hide yes)
			)
		)
		(property "MPN" "CR0402-FX-1000GLF"
			(at 191.77 60.96 0)
			(effects
				(font
					(size 1.27 1.27)
					(thickness 0.15)
				)
				(justify left bottom)
				(hide yes)
			)
		)
		(property "Manufacturer" "Bourns"
			(at 194.31 60.96 0)
			(effects
				(font
					(size 1.27 1.27)
					(thickness 0.15)
				)
				(justify left bottom)
				(hide yes)
			)
		)
		(property "License" "Apache-2.0"
			(at 196.85 60.96 0)
			(effects
				(font
					(size 1.27 1.27)
					(thickness 0.15)
				)
				(justify left bottom)
				(hide yes)
			)
		)
		(property "Author" "Antmicro"
			(at 199.39 60.96 0)
			(effects
				(font
					(size 1.27 1.27)
					(thickness 0.15)
				)
				(justify left bottom)
				(hide yes)
			)
		)
		(property "Val" "100R"
			(at 172.974 80.01 90)
			(effects
				(font
					(size 1.27 1.27)
					(thickness 0.15)
				)
				(justify right)
			)
		)
		(property "Tolerance" "1%"
			(at 181.61 60.96 0)
			(effects
				(font
					(size 1.27 1.27)
				)
				(justify left bottom)
				(hide yes)
			)
		)
		(pin "2"
		)
		(pin "1"
		)
		(instances
			(project "OCuLink to 10GbE adapter"
				(path ""
					(reference "R140")
					(unit 1)
				)
			)
			(project "thunderbolt-to-10gbe-adapter"
				(path ""
					(reference "R128")
					(unit 1)
				)
			)
		)
	)
	(symbol
		(lib_id "antmicropower:GND")
		(at 261.62 64.77 0)
		(unit 1)
		(exclude_from_sim no)
		(in_bom yes)
		(on_board yes)
		(dnp no)
		(property "Reference" "#PWR0368"
			(at 270.51 67.31 0)
			(effects
				(font
					(size 1.27 1.27)
					(thickness 0.15)
				)
				(justify left bottom)
				(hide yes)
			)
		)
		(property "Value" "GND"
			(at 261.62 68.58 0)
			(effects
				(font
					(size 1.27 1.27)
					(thickness 0.15)
				)
			)
		)
		(property "Footprint" ""
			(at 270.51 72.39 0)
			(effects
				(font
					(size 1.27 1.27)
					(thickness 0.15)
				)
				(justify left bottom)
				(hide yes)
			)
		)
		(property "Datasheet" ""
			(at 270.51 77.47 0)
			(effects
				(font
					(size 1.27 1.27)
					(thickness 0.15)
				)
				(justify left bottom)
				(hide yes)
			)
		)
		(property "Description" ""
			(at 261.62 64.77 0)
			(effects
				(font
					(size 1.27 1.27)
				)
				(hide yes)
			)
		)
		(property "Author" "Antmicro"
			(at 270.51 72.39 0)
			(effects
				(font
					(size 1.27 1.27)
					(thickness 0.15)
				)
				(justify left bottom)
				(hide yes)
			)
		)
		(property "License" "Apache-2.0"
			(at 270.51 74.93 0)
			(effects
				(font
					(size 1.27 1.27)
					(thickness 0.15)
				)
				(justify left bottom)
				(hide yes)
			)
		)
		(pin "1"
		)
		(instances
			(project "OCuLink to 10GbE adapter"
				(path ""
					(reference "#PWR0290")
					(unit 1)
				)
			)
			(project "thunderbolt-to-10gbe-adapter"
				(path ""
					(reference "#PWR0368")
					(unit 1)
				)
			)
		)
	)
	(symbol
		(lib_id "antmicroResistors0402:R_100R_0402")
		(at 118.11 81.28 90)
		(unit 1)
		(exclude_from_sim no)
		(in_bom yes)
		(on_board yes)
		(dnp no)
		(property "Reference" "R121"
			(at 119.634 77.47 90)
			(effects
				(font
					(size 1.27 1.27)
					(thickness 0.15)
				)
				(justify right)
			)
		)
		(property "Value" "R_100R_0402"
			(at 130.81 60.96 0)
			(effects
				(font
					(size 1.27 1.27)
					(thickness 0.15)
				)
				(justify left bottom)
				(hide yes)
			)
		)
		(property "Footprint" "antmicro-footprints:R_0402_1005Metric"
			(at 133.35 60.96 0)
			(effects
				(font
					(size 1.27 1.27)
					(thickness 0.15)
				)
				(justify left bottom)
				(hide yes)
			)
		)
		(property "Datasheet" "https://www.bourns.com/docs/product-datasheets/cr.pdf"
			(at 135.89 60.96 0)
			(effects
				(font
					(size 1.27 1.27)
					(thickness 0.15)
				)
				(justify left bottom)
				(hide yes)
			)
		)
		(property "Description" "SMD Chip Resistor, 100 ohm, ± 1%, 62.5 mW, 0402 [1005 Metric], Thick Film, General Purpose"
			(at 118.11 81.28 0)
			(effects
				(font
					(size 1.27 1.27)
				)
				(hide yes)
			)
		)
		(property "MPN" "CR0402-FX-1000GLF"
			(at 138.43 60.96 0)
			(effects
				(font
					(size 1.27 1.27)
					(thickness 0.15)
				)
				(justify left bottom)
				(hide yes)
			)
		)
		(property "Manufacturer" "Bourns"
			(at 140.97 60.96 0)
			(effects
				(font
					(size 1.27 1.27)
					(thickness 0.15)
				)
				(justify left bottom)
				(hide yes)
			)
		)
		(property "License" "Apache-2.0"
			(at 143.51 60.96 0)
			(effects
				(font
					(size 1.27 1.27)
					(thickness 0.15)
				)
				(justify left bottom)
				(hide yes)
			)
		)
		(property "Author" "Antmicro"
			(at 146.05 60.96 0)
			(effects
				(font
					(size 1.27 1.27)
					(thickness 0.15)
				)
				(justify left bottom)
				(hide yes)
			)
		)
		(property "Val" "100R"
			(at 119.634 80.01 90)
			(effects
				(font
					(size 1.27 1.27)
					(thickness 0.15)
				)
				(justify right)
			)
		)
		(property "Tolerance" "1%"
			(at 128.27 60.96 0)
			(effects
				(font
					(size 1.27 1.27)
				)
				(justify left bottom)
				(hide yes)
			)
		)
		(pin "2"
		)
		(pin "1"
		)
		(instances
			(project "OCuLink to 10GbE adapter"
				(path ""
					(reference "R134")
					(unit 1)
				)
			)
			(project "thunderbolt-to-10gbe-adapter"
				(path ""
					(reference "R121")
					(unit 1)
				)
			)
		)
	)
	(symbol
		(lib_id "antmicropower:GND")
		(at 118.11 83.82 0)
		(unit 1)
		(exclude_from_sim no)
		(in_bom yes)
		(on_board yes)
		(dnp no)
		(property "Reference" "#PWR0357"
			(at 127 86.36 0)
			(effects
				(font
					(size 1.27 1.27)
					(thickness 0.15)
				)
				(justify left bottom)
				(hide yes)
			)
		)
		(property "Value" "GND"
			(at 118.11 87.63 0)
			(effects
				(font
					(size 1.27 1.27)
					(thickness 0.15)
				)
			)
		)
		(property "Footprint" ""
			(at 127 91.44 0)
			(effects
				(font
					(size 1.27 1.27)
					(thickness 0.15)
				)
				(justify left bottom)
				(hide yes)
			)
		)
		(property "Datasheet" ""
			(at 127 96.52 0)
			(effects
				(font
					(size 1.27 1.27)
					(thickness 0.15)
				)
				(justify left bottom)
				(hide yes)
			)
		)
		(property "Description" ""
			(at 118.11 83.82 0)
			(effects
				(font
					(size 1.27 1.27)
				)
				(hide yes)
			)
		)
		(property "Author" "Antmicro"
			(at 127 91.44 0)
			(effects
				(font
					(size 1.27 1.27)
					(thickness 0.15)
				)
				(justify left bottom)
				(hide yes)
			)
		)
		(property "License" "Apache-2.0"
			(at 127 93.98 0)
			(effects
				(font
					(size 1.27 1.27)
					(thickness 0.15)
				)
				(justify left bottom)
				(hide yes)
			)
		)
		(pin "1"
		)
		(instances
			(project "OCuLink to 10GbE adapter"
				(path ""
					(reference "#PWR0293")
					(unit 1)
				)
			)
			(project "thunderbolt-to-10gbe-adapter"
				(path ""
					(reference "#PWR0357")
					(unit 1)
				)
			)
		)
	)
	(symbol
		(lib_id "antmicropower:GND")
		(at 269.24 64.77 0)
		(unit 1)
		(exclude_from_sim no)
		(in_bom yes)
		(on_board yes)
		(dnp no)
		(property "Reference" "#PWR0369"
			(at 278.13 67.31 0)
			(effects
				(font
					(size 1.27 1.27)
					(thickness 0.15)
				)
				(justify left bottom)
				(hide yes)
			)
		)
		(property "Value" "GND"
			(at 269.24 68.58 0)
			(effects
				(font
					(size 1.27 1.27)
					(thickness 0.15)
				)
			)
		)
		(property "Footprint" ""
			(at 278.13 72.39 0)
			(effects
				(font
					(size 1.27 1.27)
					(thickness 0.15)
				)
				(justify left bottom)
				(hide yes)
			)
		)
		(property "Datasheet" ""
			(at 278.13 77.47 0)
			(effects
				(font
					(size 1.27 1.27)
					(thickness 0.15)
				)
				(justify left bottom)
				(hide yes)
			)
		)
		(property "Description" ""
			(at 269.24 64.77 0)
			(effects
				(font
					(size 1.27 1.27)
				)
				(hide yes)
			)
		)
		(property "Author" "Antmicro"
			(at 278.13 72.39 0)
			(effects
				(font
					(size 1.27 1.27)
					(thickness 0.15)
				)
				(justify left bottom)
				(hide yes)
			)
		)
		(property "License" "Apache-2.0"
			(at 278.13 74.93 0)
			(effects
				(font
					(size 1.27 1.27)
					(thickness 0.15)
				)
				(justify left bottom)
				(hide yes)
			)
		)
		(pin "1"
		)
		(instances
			(project "OCuLink to 10GbE adapter"
				(path ""
					(reference "#PWR0291")
					(unit 1)
				)
			)
			(project "thunderbolt-to-10gbe-adapter"
				(path ""
					(reference "#PWR0369")
					(unit 1)
				)
			)
		)
	)
	(symbol
		(lib_id "antmicroResistors0402:R_10k_0402")
		(at 261.62 62.23 90)
		(unit 1)
		(exclude_from_sim no)
		(in_bom yes)
		(on_board yes)
		(dnp no)
		(property "Reference" "R132"
			(at 263.144 58.42 90)
			(effects
				(font
					(size 1.27 1.27)
					(thickness 0.15)
				)
				(justify right)
			)
		)
		(property "Value" "R_10k_0402"
			(at 274.32 41.91 0)
			(effects
				(font
					(size 1.27 1.27)
					(thickness 0.15)
				)
				(justify left bottom)
				(hide yes)
			)
		)
		(property "Footprint" "antmicro-footprints:R_0402_1005Metric"
			(at 276.86 41.91 0)
			(effects
				(font
					(size 1.27 1.27)
					(thickness 0.15)
				)
				(justify left bottom)
				(hide yes)
			)
		)
		(property "Datasheet" "https://www.bourns.com/docs/product-datasheets/cr.pdf"
			(at 279.4 41.91 0)
			(effects
				(font
					(size 1.27 1.27)
					(thickness 0.15)
				)
				(justify left bottom)
				(hide yes)
			)
		)
		(property "Description" "SMD Chip Resistor, 10 kohm, ± 1%, 62.5 mW, 0402 [1005 Metric], Thick Film, General Purpose"
			(at 261.62 62.23 0)
			(effects
				(font
					(size 1.27 1.27)
				)
				(hide yes)
			)
		)
		(property "MPN" "CR0402-FX-1002GLF"
			(at 281.94 41.91 0)
			(effects
				(font
					(size 1.27 1.27)
					(thickness 0.15)
				)
				(justify left bottom)
				(hide yes)
			)
		)
		(property "Manufacturer" "Bourns"
			(at 284.48 41.91 0)
			(effects
				(font
					(size 1.27 1.27)
					(thickness 0.15)
				)
				(justify left bottom)
				(hide yes)
			)
		)
		(property "License" "Apache-2.0"
			(at 287.02 41.91 0)
			(effects
				(font
					(size 1.27 1.27)
					(thickness 0.15)
				)
				(justify left bottom)
				(hide yes)
			)
		)
		(property "Author" "Antmicro"
			(at 289.56 41.91 0)
			(effects
				(font
					(size 1.27 1.27)
					(thickness 0.15)
				)
				(justify left bottom)
				(hide yes)
			)
		)
		(property "Val" "10k"
			(at 263.144 60.96 90)
			(effects
				(font
					(size 1.27 1.27)
					(thickness 0.15)
				)
				(justify right)
			)
		)
		(property "Tolerance" "1%"
			(at 271.78 41.91 0)
			(effects
				(font
					(size 1.27 1.27)
				)
				(justify left bottom)
				(hide yes)
			)
		)
		(pin "1"
		)
		(pin "2"
		)
		(instances
			(project ""
				(path ""
					(reference "R131")
					(unit 1)
				)
			)
			(project "thunderbolt-to-10gbe-adapter"
				(path ""
					(reference "R132")
					(unit 1)
				)
			)
		)
	)
	(symbol
		(lib_id "antmicropower:GND")
		(at 180.34 83.82 0)
		(unit 1)
		(exclude_from_sim no)
		(in_bom yes)
		(on_board yes)
		(dnp no)
		(property "Reference" "#PWR0365"
			(at 189.23 86.36 0)
			(effects
				(font
					(size 1.27 1.27)
					(thickness 0.15)
				)
				(justify left bottom)
				(hide yes)
			)
		)
		(property "Value" "GND"
			(at 180.34 87.63 0)
			(effects
				(font
					(size 1.27 1.27)
					(thickness 0.15)
				)
			)
		)
		(property "Footprint" ""
			(at 189.23 91.44 0)
			(effects
				(font
					(size 1.27 1.27)
					(thickness 0.15)
				)
				(justify left bottom)
				(hide yes)
			)
		)
		(property "Datasheet" ""
			(at 189.23 96.52 0)
			(effects
				(font
					(size 1.27 1.27)
					(thickness 0.15)
				)
				(justify left bottom)
				(hide yes)
			)
		)
		(property "Description" ""
			(at 180.34 83.82 0)
			(effects
				(font
					(size 1.27 1.27)
				)
				(hide yes)
			)
		)
		(property "Author" "Antmicro"
			(at 189.23 91.44 0)
			(effects
				(font
					(size 1.27 1.27)
					(thickness 0.15)
				)
				(justify left bottom)
				(hide yes)
			)
		)
		(property "License" "Apache-2.0"
			(at 189.23 93.98 0)
			(effects
				(font
					(size 1.27 1.27)
					(thickness 0.15)
				)
				(justify left bottom)
				(hide yes)
			)
		)
		(pin "1"
		)
		(instances
			(project "OCuLink to 10GbE adapter"
				(path ""
					(reference "#PWR0300")
					(unit 1)
				)
			)
			(project "thunderbolt-to-10gbe-adapter"
				(path ""
					(reference "#PWR0365")
					(unit 1)
				)
			)
		)
	)
	(symbol
		(lib_id "antmicroResistors0402:R_10k_0402")
		(at 276.86 62.23 90)
		(unit 1)
		(exclude_from_sim no)
		(in_bom yes)
		(on_board yes)
		(dnp no)
		(property "Reference" "R136"
			(at 278.384 58.42 90)
			(effects
				(font
					(size 1.27 1.27)
					(thickness 0.15)
				)
				(justify right)
			)
		)
		(property "Value" "R_10k_0402"
			(at 289.56 41.91 0)
			(effects
				(font
					(size 1.27 1.27)
					(thickness 0.15)
				)
				(justify left bottom)
				(hide yes)
			)
		)
		(property "Footprint" "antmicro-footprints:R_0402_1005Metric"
			(at 292.1 41.91 0)
			(effects
				(font
					(size 1.27 1.27)
					(thickness 0.15)
				)
				(justify left bottom)
				(hide yes)
			)
		)
		(property "Datasheet" "https://www.bourns.com/docs/product-datasheets/cr.pdf"
			(at 294.64 41.91 0)
			(effects
				(font
					(size 1.27 1.27)
					(thickness 0.15)
				)
				(justify left bottom)
				(hide yes)
			)
		)
		(property "Description" "SMD Chip Resistor, 10 kohm, ± 1%, 62.5 mW, 0402 [1005 Metric], Thick Film, General Purpose"
			(at 276.86 62.23 0)
			(effects
				(font
					(size 1.27 1.27)
				)
				(hide yes)
			)
		)
		(property "MPN" "CR0402-FX-1002GLF"
			(at 297.18 41.91 0)
			(effects
				(font
					(size 1.27 1.27)
					(thickness 0.15)
				)
				(justify left bottom)
				(hide yes)
			)
		)
		(property "Manufacturer" "Bourns"
			(at 299.72 41.91 0)
			(effects
				(font
					(size 1.27 1.27)
					(thickness 0.15)
				)
				(justify left bottom)
				(hide yes)
			)
		)
		(property "License" "Apache-2.0"
			(at 302.26 41.91 0)
			(effects
				(font
					(size 1.27 1.27)
					(thickness 0.15)
				)
				(justify left bottom)
				(hide yes)
			)
		)
		(property "Author" "Antmicro"
			(at 304.8 41.91 0)
			(effects
				(font
					(size 1.27 1.27)
					(thickness 0.15)
				)
				(justify left bottom)
				(hide yes)
			)
		)
		(property "Val" "10k"
			(at 278.384 60.96 90)
			(effects
				(font
					(size 1.27 1.27)
					(thickness 0.15)
				)
				(justify right)
			)
		)
		(property "Tolerance" "1%"
			(at 287.02 41.91 0)
			(effects
				(font
					(size 1.27 1.27)
				)
				(justify left bottom)
				(hide yes)
			)
		)
		(pin "1"
		)
		(pin "2"
		)
		(instances
			(project "OCuLink to 10GbE adapter"
				(path ""
					(reference "R133")
					(unit 1)
				)
			)
			(project "thunderbolt-to-10gbe-adapter"
				(path ""
					(reference "R136")
					(unit 1)
				)
			)
		)
	)
	(symbol
		(lib_id "antmicropower:GND")
		(at 153.67 83.82 0)
		(unit 1)
		(exclude_from_sim no)
		(in_bom yes)
		(on_board yes)
		(dnp no)
		(property "Reference" "#PWR0361"
			(at 162.56 86.36 0)
			(effects
				(font
					(size 1.27 1.27)
					(thickness 0.15)
				)
				(justify left bottom)
				(hide yes)
			)
		)
		(property "Value" "GND"
			(at 153.67 87.63 0)
			(effects
				(font
					(size 1.27 1.27)
					(thickness 0.15)
				)
			)
		)
		(property "Footprint" ""
			(at 162.56 91.44 0)
			(effects
				(font
					(size 1.27 1.27)
					(thickness 0.15)
				)
				(justify left bottom)
				(hide yes)
			)
		)
		(property "Datasheet" ""
			(at 162.56 96.52 0)
			(effects
				(font
					(size 1.27 1.27)
					(thickness 0.15)
				)
				(justify left bottom)
				(hide yes)
			)
		)
		(property "Description" ""
			(at 153.67 83.82 0)
			(effects
				(font
					(size 1.27 1.27)
				)
				(hide yes)
			)
		)
		(property "Author" "Antmicro"
			(at 162.56 91.44 0)
			(effects
				(font
					(size 1.27 1.27)
					(thickness 0.15)
				)
				(justify left bottom)
				(hide yes)
			)
		)
		(property "License" "Apache-2.0"
			(at 162.56 93.98 0)
			(effects
				(font
					(size 1.27 1.27)
					(thickness 0.15)
				)
				(justify left bottom)
				(hide yes)
			)
		)
		(pin "1"
		)
		(instances
			(project "OCuLink to 10GbE adapter"
				(path ""
					(reference "#PWR0297")
					(unit 1)
				)
			)
			(project "thunderbolt-to-10gbe-adapter"
				(path ""
					(reference "#PWR0361")
					(unit 1)
				)
			)
		)
	)
	(symbol
		(lib_id "antmicroResistors0402:R_100R_0402")
		(at 127 81.28 90)
		(unit 1)
		(exclude_from_sim no)
		(in_bom yes)
		(on_board yes)
		(dnp no)
		(property "Reference" "R122"
			(at 128.524 77.47 90)
			(effects
				(font
					(size 1.27 1.27)
					(thickness 0.15)
				)
				(justify right)
			)
		)
		(property "Value" "R_100R_0402"
			(at 139.7 60.96 0)
			(effects
				(font
					(size 1.27 1.27)
					(thickness 0.15)
				)
				(justify left bottom)
				(hide yes)
			)
		)
		(property "Footprint" "antmicro-footprints:R_0402_1005Metric"
			(at 142.24 60.96 0)
			(effects
				(font
					(size 1.27 1.27)
					(thickness 0.15)
				)
				(justify left bottom)
				(hide yes)
			)
		)
		(property "Datasheet" "https://www.bourns.com/docs/product-datasheets/cr.pdf"
			(at 144.78 60.96 0)
			(effects
				(font
					(size 1.27 1.27)
					(thickness 0.15)
				)
				(justify left bottom)
				(hide yes)
			)
		)
		(property "Description" "SMD Chip Resistor, 100 ohm, ± 1%, 62.5 mW, 0402 [1005 Metric], Thick Film, General Purpose"
			(at 127 81.28 0)
			(effects
				(font
					(size 1.27 1.27)
				)
				(hide yes)
			)
		)
		(property "MPN" "CR0402-FX-1000GLF"
			(at 147.32 60.96 0)
			(effects
				(font
					(size 1.27 1.27)
					(thickness 0.15)
				)
				(justify left bottom)
				(hide yes)
			)
		)
		(property "Manufacturer" "Bourns"
			(at 149.86 60.96 0)
			(effects
				(font
					(size 1.27 1.27)
					(thickness 0.15)
				)
				(justify left bottom)
				(hide yes)
			)
		)
		(property "License" "Apache-2.0"
			(at 152.4 60.96 0)
			(effects
				(font
					(size 1.27 1.27)
					(thickness 0.15)
				)
				(justify left bottom)
				(hide yes)
			)
		)
		(property "Author" "Antmicro"
			(at 154.94 60.96 0)
			(effects
				(font
					(size 1.27 1.27)
					(thickness 0.15)
				)
				(justify left bottom)
				(hide yes)
			)
		)
		(property "Val" "100R"
			(at 128.524 80.01 90)
			(effects
				(font
					(size 1.27 1.27)
					(thickness 0.15)
				)
				(justify right)
			)
		)
		(property "Tolerance" "1%"
			(at 137.16 60.96 0)
			(effects
				(font
					(size 1.27 1.27)
				)
				(justify left bottom)
				(hide yes)
			)
		)
		(pin "2"
		)
		(pin "1"
		)
		(instances
			(project "OCuLink to 10GbE adapter"
				(path ""
					(reference "R135")
					(unit 1)
				)
			)
			(project "thunderbolt-to-10gbe-adapter"
				(path ""
					(reference "R122")
					(unit 1)
				)
			)
		)
	)
	(symbol
		(lib_id "antmicroResistors0402:R_1k_0402")
		(at 261.62 46.99 90)
		(unit 1)
		(exclude_from_sim no)
		(in_bom yes)
		(on_board yes)
		(dnp no)
		(property "Reference" "R131"
			(at 263.144 43.18 90)
			(effects
				(font
					(size 1.27 1.27)
					(thickness 0.15)
				)
				(justify right)
			)
		)
		(property "Value" "R_1k_0402"
			(at 274.32 26.67 0)
			(effects
				(font
					(size 1.27 1.27)
					(thickness 0.15)
				)
				(justify left bottom)
				(hide yes)
			)
		)
		(property "Footprint" "antmicro-footprints:R_0402_1005Metric"
			(at 276.86 26.67 0)
			(effects
				(font
					(size 1.27 1.27)
					(thickness 0.15)
				)
				(justify left bottom)
				(hide yes)
			)
		)
		(property "Datasheet" "https://www.bourns.com/docs/product-datasheets/cr.pdf"
			(at 279.4 26.67 0)
			(effects
				(font
					(size 1.27 1.27)
					(thickness 0.15)
				)
				(justify left bottom)
				(hide yes)
			)
		)
		(property "Description" "SMD Chip Resistor, 1 kohm, ± 1%, 63 mW, 0402 [1005 Metric], Thick Film, General Purpose"
			(at 261.62 46.99 0)
			(effects
				(font
					(size 1.27 1.27)
				)
				(hide yes)
			)
		)
		(property "MPN" "CR0402-FX-1001GLF"
			(at 281.94 26.67 0)
			(effects
				(font
					(size 1.27 1.27)
					(thickness 0.15)
				)
				(justify left bottom)
				(hide yes)
			)
		)
		(property "Manufacturer" "Bourns"
			(at 284.48 26.67 0)
			(effects
				(font
					(size 1.27 1.27)
					(thickness 0.15)
				)
				(justify left bottom)
				(hide yes)
			)
		)
		(property "License" "Apache-2.0"
			(at 287.02 26.67 0)
			(effects
				(font
					(size 1.27 1.27)
					(thickness 0.15)
				)
				(justify left bottom)
				(hide yes)
			)
		)
		(property "Author" "Antmicro"
			(at 289.56 26.67 0)
			(effects
				(font
					(size 1.27 1.27)
					(thickness 0.15)
				)
				(justify left bottom)
				(hide yes)
			)
		)
		(property "Val" "1k"
			(at 263.144 45.72 90)
			(effects
				(font
					(size 1.27 1.27)
					(thickness 0.15)
				)
				(justify right)
			)
		)
		(property "Tolerance" "1%"
			(at 271.78 26.67 0)
			(effects
				(font
					(size 1.27 1.27)
				)
				(justify left bottom)
				(hide yes)
			)
		)
		(pin "2"
		)
		(pin "1"
		)
		(instances
			(project ""
				(path ""
					(reference "R128")
					(unit 1)
				)
			)
			(project "thunderbolt-to-10gbe-adapter"
				(path ""
					(reference "R131")
					(unit 1)
				)
			)
		)
	)
	(symbol
		(lib_id "antmicroResistors0402:R_100R_0402")
		(at 144.78 81.28 90)
		(unit 1)
		(exclude_from_sim no)
		(in_bom yes)
		(on_board yes)
		(dnp no)
		(property "Reference" "R124"
			(at 146.304 77.47 90)
			(effects
				(font
					(size 1.27 1.27)
					(thickness 0.15)
				)
				(justify right)
			)
		)
		(property "Value" "R_100R_0402"
			(at 157.48 60.96 0)
			(effects
				(font
					(size 1.27 1.27)
					(thickness 0.15)
				)
				(justify left bottom)
				(hide yes)
			)
		)
		(property "Footprint" "antmicro-footprints:R_0402_1005Metric"
			(at 160.02 60.96 0)
			(effects
				(font
					(size 1.27 1.27)
					(thickness 0.15)
				)
				(justify left bottom)
				(hide yes)
			)
		)
		(property "Datasheet" "https://www.bourns.com/docs/product-datasheets/cr.pdf"
			(at 162.56 60.96 0)
			(effects
				(font
					(size 1.27 1.27)
					(thickness 0.15)
				)
				(justify left bottom)
				(hide yes)
			)
		)
		(property "Description" "SMD Chip Resistor, 100 ohm, ± 1%, 62.5 mW, 0402 [1005 Metric], Thick Film, General Purpose"
			(at 144.78 81.28 0)
			(effects
				(font
					(size 1.27 1.27)
				)
				(hide yes)
			)
		)
		(property "MPN" "CR0402-FX-1000GLF"
			(at 165.1 60.96 0)
			(effects
				(font
					(size 1.27 1.27)
					(thickness 0.15)
				)
				(justify left bottom)
				(hide yes)
			)
		)
		(property "Manufacturer" "Bourns"
			(at 167.64 60.96 0)
			(effects
				(font
					(size 1.27 1.27)
					(thickness 0.15)
				)
				(justify left bottom)
				(hide yes)
			)
		)
		(property "License" "Apache-2.0"
			(at 170.18 60.96 0)
			(effects
				(font
					(size 1.27 1.27)
					(thickness 0.15)
				)
				(justify left bottom)
				(hide yes)
			)
		)
		(property "Author" "Antmicro"
			(at 172.72 60.96 0)
			(effects
				(font
					(size 1.27 1.27)
					(thickness 0.15)
				)
				(justify left bottom)
				(hide yes)
			)
		)
		(property "Val" "100R"
			(at 146.304 80.01 90)
			(effects
				(font
					(size 1.27 1.27)
					(thickness 0.15)
				)
				(justify right)
			)
		)
		(property "Tolerance" "1%"
			(at 154.94 60.96 0)
			(effects
				(font
					(size 1.27 1.27)
				)
				(justify left bottom)
				(hide yes)
			)
		)
		(pin "2"
		)
		(pin "1"
		)
		(instances
			(project "OCuLink to 10GbE adapter"
				(path ""
					(reference "R137")
					(unit 1)
				)
			)
			(project "thunderbolt-to-10gbe-adapter"
				(path ""
					(reference "R124")
					(unit 1)
				)
			)
		)
	)
	(symbol
		(lib_id "antmicropower:GND")
		(at 135.89 83.82 0)
		(unit 1)
		(exclude_from_sim no)
		(in_bom yes)
		(on_board yes)
		(dnp no)
		(property "Reference" "#PWR0359"
			(at 144.78 86.36 0)
			(effects
				(font
					(size 1.27 1.27)
					(thickness 0.15)
				)
				(justify left bottom)
				(hide yes)
			)
		)
		(property "Value" "GND"
			(at 135.89 87.63 0)
			(effects
				(font
					(size 1.27 1.27)
					(thickness 0.15)
				)
			)
		)
		(property "Footprint" ""
			(at 144.78 91.44 0)
			(effects
				(font
					(size 1.27 1.27)
					(thickness 0.15)
				)
				(justify left bottom)
				(hide yes)
			)
		)
		(property "Datasheet" ""
			(at 144.78 96.52 0)
			(effects
				(font
					(size 1.27 1.27)
					(thickness 0.15)
				)
				(justify left bottom)
				(hide yes)
			)
		)
		(property "Description" ""
			(at 135.89 83.82 0)
			(effects
				(font
					(size 1.27 1.27)
				)
				(hide yes)
			)
		)
		(property "Author" "Antmicro"
			(at 144.78 91.44 0)
			(effects
				(font
					(size 1.27 1.27)
					(thickness 0.15)
				)
				(justify left bottom)
				(hide yes)
			)
		)
		(property "License" "Apache-2.0"
			(at 144.78 93.98 0)
			(effects
				(font
					(size 1.27 1.27)
					(thickness 0.15)
				)
				(justify left bottom)
				(hide yes)
			)
		)
		(pin "1"
		)
		(instances
			(project "OCuLink to 10GbE adapter"
				(path ""
					(reference "#PWR0295")
					(unit 1)
				)
			)
			(project "thunderbolt-to-10gbe-adapter"
				(path ""
					(reference "#PWR0359")
					(unit 1)
				)
			)
		)
	)
	(symbol
		(lib_id "antmicroInterfaceControllers:EZX710AT2_S_LMR5")
		(at 195.58 179.07 0)
		(unit 7)
		(exclude_from_sim no)
		(in_bom yes)
		(on_board yes)
		(dnp no)
		(fields_autoplaced yes)
		(property "Reference" "U14"
			(at 218.44 171.45 0)
			(effects
				(font
					(size 1.27 1.27)
					(thickness 0.15)
				)
			)
		)
		(property "Value" "EZX710AT2_S_LMR5"
			(at 271.78 184.15 0)
			(effects
				(font
					(size 1.27 1.27)
					(thickness 0.15)
				)
				(justify left bottom)
				(hide yes)
			)
		)
		(property "Footprint" "antmicro-footprints:FCBGA-503_22x22mm_Layout21x24_P1mm"
			(at 271.78 186.69 0)
			(effects
				(font
					(size 1.27 1.27)
					(thickness 0.15)
				)
				(justify left bottom)
				(hide yes)
			)
		)
		(property "Datasheet" "https://www.google.com/url?sa=t&source=web&rct=j&opi=89978449&url=https://cdrdv2-public.intel.com/596333/596333_X710-TM4_Datasheet_v_2_4.pdf&ved=2ahUKEwiSuv20_sCOAxXVCRAIHdxGO_UQFnoECBEQAQ&usg=AOvVaw1CjGyrGWE8ZvOdw4VBsY6U"
			(at 271.78 189.23 0)
			(effects
				(font
					(size 1.27 1.27)
					(thickness 0.15)
				)
				(justify left bottom)
				(hide yes)
			)
		)
		(property "Description" "Ethernet ICs Intel Ethernet Controller 10 Gigabit X7"
			(at 271.78 191.77 0)
			(effects
				(font
					(size 1.27 1.27)
					(thickness 0.15)
				)
				(justify left bottom)
				(hide yes)
			)
		)
		(property "MPN" "EZX710AT2 S LMR5"
			(at 218.44 173.99 0)
			(effects
				(font
					(size 1.27 1.27)
					(thickness 0.15)
				)
			)
		)
		(property "Manufacturer" "Intel"
			(at 271.78 194.31 0)
			(effects
				(font
					(size 1.27 1.27)
					(thickness 0.15)
				)
				(justify left bottom)
				(hide yes)
			)
		)
		(property "Author" "Antmicro"
			(at 271.78 196.85 0)
			(effects
				(font
					(size 1.27 1.27)
					(thickness 0.15)
				)
				(justify left bottom)
				(hide yes)
			)
		)
		(property "License" "Apache-2.0"
			(at 271.78 199.39 0)
			(effects
				(font
					(size 1.27 1.27)
					(thickness 0.15)
				)
				(justify left bottom)
				(hide yes)
			)
		)
		(pin "B26"
		)
		(pin "E7"
		)
		(pin "G9"
		)
		(pin "E5"
		)
		(pin "A17"
		)
		(pin "J15"
		)
		(pin "P34"
		)
		(pin "AD30"
		)
		(pin "J7"
		)
		(pin "C1"
		)
		(pin "G37"
		)
		(pin "N37"
		)
		(pin "F38"
		)
		(pin "B2"
		)
		(pin "N29"
		)
		(pin "D4"
		)
		(pin "Y24"
		)
		(pin "N35"
		)
		(pin "C5"
		)
		(pin "V42"
		)
		(pin "M20"
		)
		(pin "P10"
		)
		(pin "L37"
		)
		(pin "B34"
		)
		(pin "U37"
		)
		(pin "AC7"
		)
		(pin "M4"
		)
		(pin "U35"
		)
		(pin "D18"
		)
		(pin "H16"
		)
		(pin "V30"
		)
		(pin "B38"
		)
		(pin "W29"
		)
		(pin "AB22"
		)
		(pin "AC15"
		)
		(pin "B28"
		)
		(pin "G3"
		)
		(pin "P32"
		)
		(pin "H14"
		)
		(pin "G13"
		)
		(pin "B30"
		)
		(pin "D22"
		)
		(pin "V10"
		)
		(pin "B24"
		)
		(pin "AD4"
		)
		(pin "AC5"
		)
		(pin "AA5"
		)
		(pin "V24"
		)
		(pin "V6"
		)
		(pin "D10"
		)
		(pin "AD20"
		)
		(pin "T26"
		)
		(pin "T10"
		)
		(pin "T12"
		)
		(pin "AD6"
		)
		(pin "H8"
		)
		(pin "H28"
		)
		(pin "N15"
		)
		(pin "AC29"
		)
		(pin "N17"
		)
		(pin "W31"
		)
		(pin "Y12"
		)
		(pin "W23"
		)
		(pin "AD32"
		)
		(pin "AB16"
		)
		(pin "T28"
		)
		(pin "D24"
		)
		(pin "D26"
		)
		(pin "G17"
		)
		(pin "K32"
		)
		(pin "F24"
		)
		(pin "F26"
		)
		(pin "J31"
		)
		(pin "T30"
		)
		(pin "AD34"
		)
		(pin "AA27"
		)
		(pin "R17"
		)
		(pin "W13"
		)
		(pin "M26"
		)
		(pin "C9"
		)
		(pin "AA41"
		)
		(pin "AC27"
		)
		(pin "K2"
		)
		(pin "AB20"
		)
		(pin "R7"
		)
		(pin "N39"
		)
		(pin "D6"
		)
		(pin "M22"
		)
		(pin "M2"
		)
		(pin "AC9"
		)
		(pin "A3"
		)
		(pin "P2"
		)
		(pin "AA33"
		)
		(pin "A23"
		)
		(pin "E35"
		)
		(pin "U3"
		)
		(pin "V36"
		)
		(pin "K42"
		)
		(pin "R41"
		)
		(pin "R1"
		)
		(pin "AD22"
		)
		(pin "W7"
		)
		(pin "AB18"
		)
		(pin "E19"
		)
		(pin "AB12"
		)
		(pin "AD28"
		)
		(pin "AD40"
		)
		(pin "J1"
		)
		(pin "Y6"
		)
		(pin "Y8"
		)
		(pin "H36"
		)
		(pin "C13"
		)
		(pin "C23"
		)
		(pin "Y38"
		)
		(pin "U21"
		)
		(pin "F32"
		)
		(pin "F34"
		)
		(pin "A25"
		)
		(pin "N23"
		)
		(pin "W41"
		)
		(pin "AC31"
		)
		(pin "D12"
		)
		(pin "K34"
		)
		(pin "AA23"
		)
		(pin "AC17"
		)
		(pin "V22"
		)
		(pin "AA39"
		)
		(pin "J41"
		)
		(pin "V14"
		)
		(pin "U23"
		)
		(pin "V16"
		)
		(pin "W35"
		)
		(pin "AC21"
		)
		(pin "D32"
		)
		(pin "L1"
		)
		(pin "P24"
		)
		(pin "J3"
		)
		(pin "AC41"
		)
		(pin "AD14"
		)
		(pin "K22"
		)
		(pin "A11"
		)
		(pin "AA15"
		)
		(pin "F2"
		)
		(pin "A9"
		)
		(pin "N27"
		)
		(pin "C19"
		)
		(pin "K30"
		)
		(pin "L23"
		)
		(pin "N41"
		)
		(pin "F20"
		)
		(pin "AB28"
		)
		(pin "AD12"
		)
		(pin "C21"
		)
		(pin "U9"
		)
		(pin "V20"
		)
		(pin "D20"
		)
		(pin "L21"
		)
		(pin "R15"
		)
		(pin "K4"
		)
		(pin "N1"
		)
		(pin "H12"
		)
		(pin "J23"
		)
		(pin "J5"
		)
		(pin "E9"
		)
		(pin "M28"
		)
		(pin "U1"
		)
		(pin "Y2"
		)
		(pin "G5"
		)
		(pin "K20"
		)
		(pin "M18"
		)
		(pin "V2"
		)
		(pin "AC39"
		)
		(pin "T32"
		)
		(pin "E25"
		)
		(pin "AD38"
		)
		(pin "H26"
		)
		(pin "AA31"
		)
		(pin "G31"
		)
		(pin "U27"
		)
		(pin "U17"
		)
		(pin "C11"
		)
		(pin "N3"
		)
		(pin "A37"
		)
		(pin "F6"
		)
		(pin "Y30"
		)
		(pin "U7"
		)
		(pin "G15"
		)
		(pin "C29"
		)
		(pin "E39"
		)
		(pin "A35"
		)
		(pin "L3"
		)
		(pin "N25"
		)
		(pin "R25"
		)
		(pin "J37"
		)
		(pin "H42"
		)
		(pin "AD24"
		)
		(pin "B14"
		)
		(pin "P6"
		)
		(pin "R31"
		)
		(pin "A5"
		)
		(pin "D14"
		)
		(pin "AB10"
		)
		(pin "B18"
		)
		(pin "A27"
		)
		(pin "T40"
		)
		(pin "AB40"
		)
		(pin "P4"
		)
		(pin "AA35"
		)
		(pin "F36"
		)
		(pin "K18"
		)
		(pin "K38"
		)
		(pin "N33"
		)
		(pin "Y26"
		)
		(pin "Y28"
		)
		(pin "G21"
		)
		(pin "AA1"
		)
		(pin "AB2"
		)
		(pin "V38"
		)
		(pin "J9"
		)
		(pin "B6"
		)
		(pin "L35"
		)
		(pin "N7"
		)
		(pin "AC1"
		)
		(pin "E23"
		)
		(pin "F40"
		)
		(pin "F42"
		)
		(pin "P36"
		)
		(pin "F4"
		)
		(pin "AD16"
		)
		(pin "R11"
		)
		(pin "R27"
		)
		(pin "J13"
		)
		(pin "M10"
		)
		(pin "Y4"
		)
		(pin "Y40"
		)
		(pin "L27"
		)
		(pin "L9"
		)
		(pin "K10"
		)
		(pin "L39"
		)
		(pin "U5"
		)
		(pin "AB42"
		)
		(pin "R5"
		)
		(pin "G23"
		)
		(pin "M8"
		)
		(pin "AD8"
		)
		(pin "M16"
		)
		(pin "M12"
		)
		(pin "E3"
		)
		(pin "B12"
		)
		(pin "R23"
		)
		(pin "W25"
		)
		(pin "H4"
		)
		(pin "F8"
		)
		(pin "AC23"
		)
		(pin "AA3"
		)
		(pin "B10"
		)
		(pin "E31"
		)
		(pin "E33"
		)
		(pin "G1"
		)
		(pin "F18"
		)
		(pin "W17"
		)
		(pin "K36"
		)
		(pin "AB26"
		)
		(pin "R13"
		)
		(pin "AB32"
		)
		(pin "V18"
		)
		(pin "D16"
		)
		(pin "AA37"
		)
		(pin "C31"
		)
		(pin "C41"
		)
		(pin "A41"
		)
		(pin "E1"
		)
		(pin "P38"
		)
		(pin "U19"
		)
		(pin "R29"
		)
		(pin "E37"
		)
		(pin "E29"
		)
		(pin "A21"
		)
		(pin "A31"
		)
		(pin "U29"
		)
		(pin "AB34"
		)
		(pin "E17"
		)
		(pin "W15"
		)
		(pin "H40"
		)
		(pin "M24"
		)
		(pin "U15"
		)
		(pin "H2"
		)
		(pin "N21"
		)
		(pin "W33"
		)
		(pin "J29"
		)
		(pin "T42"
		)
		(pin "A13"
		)
		(pin "AD26"
		)
		(pin "P28"
		)
		(pin "T24"
		)
		(pin "F12"
		)
		(pin "AD2"
		)
		(pin "H34"
		)
		(pin "J33"
		)
		(pin "P40"
		)
		(pin "C17"
		)
		(pin "W19"
		)
		(pin "M6"
		)
		(pin "H6"
		)
		(pin "M40"
		)
		(pin "D30"
		)
		(pin "F10"
		)
		(pin "Y14"
		)
		(pin "L29"
		)
		(pin "P22"
		)
		(pin "W1"
		)
		(pin "V28"
		)
		(pin "E11"
		)
		(pin "J25"
		)
		(pin "G27"
		)
		(pin "M34"
		)
		(pin "Y18"
		)
		(pin "K8"
		)
		(pin "AC35"
		)
		(pin "AD36"
		)
		(pin "G19"
		)
		(pin "G41"
		)
		(pin "W3"
		)
		(pin "C37"
		)
		(pin "C27"
		)
		(pin "Y22"
		)
		(pin "C35"
		)
		(pin "L41"
		)
		(pin "P30"
		)
		(pin "V8"
		)
		(pin "AB30"
		)
		(pin "A29"
		)
		(pin "B22"
		)
		(pin "B32"
		)
		(pin "T36"
		)
		(pin "AA17"
		)
		(pin "K12"
		)
		(pin "P8"
		)
		(pin "T22"
		)
		(pin "C15"
		)
		(pin "W9"
		)
		(pin "W11"
		)
		(pin "P42"
		)
		(pin "T6"
		)
		(pin "B40"
		)
		(pin "N9"
		)
		(pin "K6"
		)
		(pin "A33"
		)
		(pin "T38"
		)
		(pin "J35"
		)
		(pin "E41"
		)
		(pin "T2"
		)
		(pin "C3"
		)
		(pin "R3"
		)
		(pin "D8"
		)
		(pin "F28"
		)
		(pin "F30"
		)
		(pin "Y32"
		)
		(pin "Y36"
		)
		(pin "AC25"
		)
		(pin "T4"
		)
		(pin "V26"
		)
		(pin "B16"
		)
		(pin "V32"
		)
		(pin "H10"
		)
		(pin "A7"
		)
		(pin "R9"
		)
		(pin "N11"
		)
		(pin "R37"
		)
		(pin "W37"
		)
		(pin "V4"
		)
		(pin "T14"
		)
		(pin "T16"
		)
		(pin "J21"
		)
		(pin "AB14"
		)
		(pin "J17"
		)
		(pin "W5"
		)
		(pin "D34"
		)
		(pin "Y34"
		)
		(pin "M36"
		)
		(pin "AA25"
		)
		(pin "B4"
		)
		(pin "AA29"
		)
		(pin "K16"
		)
		(pin "V40"
		)
		(pin "AC37"
		)
		(pin "AB24"
		)
		(pin "AD18"
		)
		(pin "AA7"
		)
		(pin "V12"
		)
		(pin "AC13"
		)
		(pin "T8"
		)
		(pin "E21"
		)
		(pin "A19"
		)
		(pin "E27"
		)
		(pin "K14"
		)
		(pin "AA13"
		)
		(pin "P16"
		)
		(pin "P18"
		)
		(pin "H30"
		)
		(pin "N31"
		)
		(pin "P12"
		)
		(pin "P14"
		)
		(pin "B42"
		)
		(pin "G25"
		)
		(pin "U25"
		)
		(pin "A39"
		)
		(pin "J11"
		)
		(pin "G11"
		)
		(pin "G29"
		)
		(pin "R19"
		)
		(pin "AC11"
		)
		(pin "F22"
		)
		(pin "W39"
		)
		(pin "AA9"
		)
		(pin "AB38"
		)
		(pin "L31"
		)
		(pin "T34"
		)
		(pin "J39"
		)
		(pin "F14"
		)
		(pin "H24"
		)
		(pin "G35"
		)
		(pin "W21"
		)
		(pin "K40"
		)
		(pin "N19"
		)
		(pin "B20"
		)
		(pin "U31"
		)
		(pin "R21"
		)
		(pin "R39"
		)
		(pin "P20"
		)
		(pin "R35"
		)
		(pin "AD42"
		)
		(pin "K24"
		)
		(pin "AB4"
		)
		(pin "AC33"
		)
		(pin "B8"
		)
		(pin "U33"
		)
		(pin "H32"
		)
		(pin "L33"
		)
		(pin "J19"
		)
		(pin "U13"
		)
		(pin "C39"
		)
		(pin "H22"
		)
		(pin "AD10"
		)
		(pin "Y20"
		)
		(pin "E15"
		)
		(pin "AA21"
		)
		(pin "K26"
		)
		(pin "C25"
		)
		(pin "M42"
		)
		(pin "U41"
		)
		(pin "Y16"
		)
		(pin "D28"
		)
		(pin "D36"
		)
		(pin "Y10"
		)
		(pin "AC19"
		)
		(pin "AB8"
		)
		(pin "AB36"
		)
		(pin "P26"
		)
		(pin "D38"
		)
		(pin "D40"
		)
		(pin "AA19"
		)
		(pin "E13"
		)
		(pin "A15"
		)
		(pin "H20"
		)
		(pin "K28"
		)
		(pin "F16"
		)
		(pin "W27"
		)
		(pin "D42"
		)
		(pin "AB6"
		)
		(pin "M14"
		)
		(pin "M32"
		)
		(pin "N5"
		)
		(pin "U11"
		)
		(pin "J27"
		)
		(pin "M30"
		)
		(pin "C33"
		)
		(pin "C7"
		)
		(pin "L15"
		)
		(pin "G33"
		)
		(pin "L19"
		)
		(pin "L17"
		)
		(pin "L5"
		)
		(pin "L25"
		)
		(pin "M38"
		)
		(pin "T18"
		)
		(pin "T20"
		)
		(pin "H18"
		)
		(pin "G7"
		)
		(pin "B36"
		)
		(pin "U39"
		)
		(pin "G39"
		)
		(pin "D2"
		)
		(pin "R33"
		)
		(pin "L11"
		)
		(pin "AC3"
		)
		(pin "AA11"
		)
		(pin "H38"
		)
		(pin "N13"
		)
		(pin "L13"
		)
		(pin "L7"
		)
		(pin "Y42"
		)
		(pin "V34"
		)
		(instances
			(project "OCuLink to 10GbE adapter"
				(path ""
					(reference "U9")
					(unit 7)
				)
			)
			(project "thunderbolt-to-10gbe-adapter"
				(path ""
					(reference "U14")
					(unit 7)
				)
			)
		)
	)
	(symbol
		(lib_id "antmicropower:GND")
		(at 241.3 250.19 0)
		(unit 1)
		(exclude_from_sim no)
		(in_bom yes)
		(on_board yes)
		(dnp no)
		(property "Reference" "#PWR0367"
			(at 250.19 252.73 0)
			(effects
				(font
					(size 1.27 1.27)
					(thickness 0.15)
				)
				(justify left bottom)
				(hide yes)
			)
		)
		(property "Value" "GND"
			(at 241.3 254 0)
			(effects
				(font
					(size 1.27 1.27)
					(thickness 0.15)
				)
			)
		)
		(property "Footprint" ""
			(at 250.19 257.81 0)
			(effects
				(font
					(size 1.27 1.27)
					(thickness 0.15)
				)
				(justify left bottom)
				(hide yes)
			)
		)
		(property "Datasheet" ""
			(at 250.19 262.89 0)
			(effects
				(font
					(size 1.27 1.27)
					(thickness 0.15)
				)
				(justify left bottom)
				(hide yes)
			)
		)
		(property "Description" ""
			(at 241.3 250.19 0)
			(effects
				(font
					(size 1.27 1.27)
				)
				(hide yes)
			)
		)
		(property "Author" "Antmicro"
			(at 250.19 257.81 0)
			(effects
				(font
					(size 1.27 1.27)
					(thickness 0.15)
				)
				(justify left bottom)
				(hide yes)
			)
		)
		(property "License" "Apache-2.0"
			(at 250.19 260.35 0)
			(effects
				(font
					(size 1.27 1.27)
					(thickness 0.15)
				)
				(justify left bottom)
				(hide yes)
			)
		)
		(pin "1"
		)
		(instances
			(project "OCuLink to 10GbE adapter"
				(path ""
					(reference "#PWR0317")
					(unit 1)
				)
			)
			(project "thunderbolt-to-10gbe-adapter"
				(path ""
					(reference "#PWR0367")
					(unit 1)
				)
			)
		)
	)
	(symbol
		(lib_id "antmicroResistors0402:R_1k_0402")
		(at 173.99 176.53 90)
		(unit 1)
		(exclude_from_sim no)
		(in_bom yes)
		(on_board yes)
		(dnp no)
		(property "Reference" "R129"
			(at 175.514 172.72 90)
			(effects
				(font
					(size 1.27 1.27)
					(thickness 0.15)
				)
				(justify right)
			)
		)
		(property "Value" "R_1k_0402"
			(at 186.69 156.21 0)
			(effects
				(font
					(size 1.27 1.27)
					(thickness 0.15)
				)
				(justify left bottom)
				(hide yes)
			)
		)
		(property "Footprint" "antmicro-footprints:R_0402_1005Metric"
			(at 189.23 156.21 0)
			(effects
				(font
					(size 1.27 1.27)
					(thickness 0.15)
				)
				(justify left bottom)
				(hide yes)
			)
		)
		(property "Datasheet" "https://www.bourns.com/docs/product-datasheets/cr.pdf"
			(at 191.77 156.21 0)
			(effects
				(font
					(size 1.27 1.27)
					(thickness 0.15)
				)
				(justify left bottom)
				(hide yes)
			)
		)
		(property "Description" "SMD Chip Resistor, 1 kohm, ± 1%, 63 mW, 0402 [1005 Metric], Thick Film, General Purpose"
			(at 173.99 176.53 0)
			(effects
				(font
					(size 1.27 1.27)
				)
				(hide yes)
			)
		)
		(property "MPN" "CR0402-FX-1001GLF"
			(at 194.31 156.21 0)
			(effects
				(font
					(size 1.27 1.27)
					(thickness 0.15)
				)
				(justify left bottom)
				(hide yes)
			)
		)
		(property "Manufacturer" "Bourns"
			(at 196.85 156.21 0)
			(effects
				(font
					(size 1.27 1.27)
					(thickness 0.15)
				)
				(justify left bottom)
				(hide yes)
			)
		)
		(property "License" "Apache-2.0"
			(at 199.39 156.21 0)
			(effects
				(font
					(size 1.27 1.27)
					(thickness 0.15)
				)
				(justify left bottom)
				(hide yes)
			)
		)
		(property "Author" "Antmicro"
			(at 201.93 156.21 0)
			(effects
				(font
					(size 1.27 1.27)
					(thickness 0.15)
				)
				(justify left bottom)
				(hide yes)
			)
		)
		(property "Val" "1k"
			(at 175.514 175.26 90)
			(effects
				(font
					(size 1.27 1.27)
					(thickness 0.15)
				)
				(justify right)
			)
		)
		(property "Tolerance" "1%"
			(at 184.15 156.21 0)
			(effects
				(font
					(size 1.27 1.27)
				)
				(justify left bottom)
				(hide yes)
			)
		)
		(pin "2"
		)
		(pin "1"
		)
		(instances
			(project "OCuLink to 10GbE adapter"
				(path ""
					(reference "R143")
					(unit 1)
				)
			)
			(project "thunderbolt-to-10gbe-adapter"
				(path ""
					(reference "R129")
					(unit 1)
				)
			)
		)
	)
	(symbol
		(lib_id "antmicroResistors0402:R_100R_0402")
		(at 162.56 81.28 90)
		(unit 1)
		(exclude_from_sim no)
		(in_bom yes)
		(on_board yes)
		(dnp no)
		(property "Reference" "R126"
			(at 164.084 77.47 90)
			(effects
				(font
					(size 1.27 1.27)
					(thickness 0.15)
				)
				(justify right)
			)
		)
		(property "Value" "R_100R_0402"
			(at 175.26 60.96 0)
			(effects
				(font
					(size 1.27 1.27)
					(thickness 0.15)
				)
				(justify left bottom)
				(hide yes)
			)
		)
		(property "Footprint" "antmicro-footprints:R_0402_1005Metric"
			(at 177.8 60.96 0)
			(effects
				(font
					(size 1.27 1.27)
					(thickness 0.15)
				)
				(justify left bottom)
				(hide yes)
			)
		)
		(property "Datasheet" "https://www.bourns.com/docs/product-datasheets/cr.pdf"
			(at 180.34 60.96 0)
			(effects
				(font
					(size 1.27 1.27)
					(thickness 0.15)
				)
				(justify left bottom)
				(hide yes)
			)
		)
		(property "Description" "SMD Chip Resistor, 100 ohm, ± 1%, 62.5 mW, 0402 [1005 Metric], Thick Film, General Purpose"
			(at 162.56 81.28 0)
			(effects
				(font
					(size 1.27 1.27)
				)
				(hide yes)
			)
		)
		(property "MPN" "CR0402-FX-1000GLF"
			(at 182.88 60.96 0)
			(effects
				(font
					(size 1.27 1.27)
					(thickness 0.15)
				)
				(justify left bottom)
				(hide yes)
			)
		)
		(property "Manufacturer" "Bourns"
			(at 185.42 60.96 0)
			(effects
				(font
					(size 1.27 1.27)
					(thickness 0.15)
				)
				(justify left bottom)
				(hide yes)
			)
		)
		(property "License" "Apache-2.0"
			(at 187.96 60.96 0)
			(effects
				(font
					(size 1.27 1.27)
					(thickness 0.15)
				)
				(justify left bottom)
				(hide yes)
			)
		)
		(property "Author" "Antmicro"
			(at 190.5 60.96 0)
			(effects
				(font
					(size 1.27 1.27)
					(thickness 0.15)
				)
				(justify left bottom)
				(hide yes)
			)
		)
		(property "Val" "100R"
			(at 164.084 80.01 90)
			(effects
				(font
					(size 1.27 1.27)
					(thickness 0.15)
				)
				(justify right)
			)
		)
		(property "Tolerance" "1%"
			(at 172.72 60.96 0)
			(effects
				(font
					(size 1.27 1.27)
				)
				(justify left bottom)
				(hide yes)
			)
		)
		(pin "2"
		)
		(pin "1"
		)
		(instances
			(project "OCuLink to 10GbE adapter"
				(path ""
					(reference "R139")
					(unit 1)
				)
			)
			(project "thunderbolt-to-10gbe-adapter"
				(path ""
					(reference "R126")
					(unit 1)
				)
			)
		)
	)
	(symbol
		(lib_id "antmicropower:GND")
		(at 162.56 83.82 0)
		(unit 1)
		(exclude_from_sim no)
		(in_bom yes)
		(on_board yes)
		(dnp no)
		(property "Reference" "#PWR0362"
			(at 171.45 86.36 0)
			(effects
				(font
					(size 1.27 1.27)
					(thickness 0.15)
				)
				(justify left bottom)
				(hide yes)
			)
		)
		(property "Value" "GND"
			(at 162.56 87.63 0)
			(effects
				(font
					(size 1.27 1.27)
					(thickness 0.15)
				)
			)
		)
		(property "Footprint" ""
			(at 171.45 91.44 0)
			(effects
				(font
					(size 1.27 1.27)
					(thickness 0.15)
				)
				(justify left bottom)
				(hide yes)
			)
		)
		(property "Datasheet" ""
			(at 171.45 96.52 0)
			(effects
				(font
					(size 1.27 1.27)
					(thickness 0.15)
				)
				(justify left bottom)
				(hide yes)
			)
		)
		(property "Description" ""
			(at 162.56 83.82 0)
			(effects
				(font
					(size 1.27 1.27)
				)
				(hide yes)
			)
		)
		(property "Author" "Antmicro"
			(at 171.45 91.44 0)
			(effects
				(font
					(size 1.27 1.27)
					(thickness 0.15)
				)
				(justify left bottom)
				(hide yes)
			)
		)
		(property "License" "Apache-2.0"
			(at 171.45 93.98 0)
			(effects
				(font
					(size 1.27 1.27)
					(thickness 0.15)
				)
				(justify left bottom)
				(hide yes)
			)
		)
		(pin "1"
		)
		(instances
			(project "OCuLink to 10GbE adapter"
				(path ""
					(reference "#PWR0298")
					(unit 1)
				)
			)
			(project "thunderbolt-to-10gbe-adapter"
				(path ""
					(reference "#PWR0362")
					(unit 1)
				)
			)
		)
	)
	(symbol
		(lib_id "antmicropower:GND")
		(at 127 83.82 0)
		(unit 1)
		(exclude_from_sim no)
		(in_bom yes)
		(on_board yes)
		(dnp no)
		(property "Reference" "#PWR0358"
			(at 135.89 86.36 0)
			(effects
				(font
					(size 1.27 1.27)
					(thickness 0.15)
				)
				(justify left bottom)
				(hide yes)
			)
		)
		(property "Value" "GND"
			(at 127 87.63 0)
			(effects
				(font
					(size 1.27 1.27)
					(thickness 0.15)
				)
			)
		)
		(property "Footprint" ""
			(at 135.89 91.44 0)
			(effects
				(font
					(size 1.27 1.27)
					(thickness 0.15)
				)
				(justify left bottom)
				(hide yes)
			)
		)
		(property "Datasheet" ""
			(at 135.89 96.52 0)
			(effects
				(font
					(size 1.27 1.27)
					(thickness 0.15)
				)
				(justify left bottom)
				(hide yes)
			)
		)
		(property "Description" ""
			(at 127 83.82 0)
			(effects
				(font
					(size 1.27 1.27)
				)
				(hide yes)
			)
		)
		(property "Author" "Antmicro"
			(at 135.89 91.44 0)
			(effects
				(font
					(size 1.27 1.27)
					(thickness 0.15)
				)
				(justify left bottom)
				(hide yes)
			)
		)
		(property "License" "Apache-2.0"
			(at 135.89 93.98 0)
			(effects
				(font
					(size 1.27 1.27)
					(thickness 0.15)
				)
				(justify left bottom)
				(hide yes)
			)
		)
		(pin "1"
		)
		(instances
			(project "OCuLink to 10GbE adapter"
				(path ""
					(reference "#PWR0294")
					(unit 1)
				)
			)
			(project "thunderbolt-to-10gbe-adapter"
				(path ""
					(reference "#PWR0358")
					(unit 1)
				)
			)
		)
	)
	(symbol
		(lib_id "antmicroInterfaceControllers:EZX710AT2_S_LMR5")
		(at 195.58 49.53 0)
		(unit 5)
		(exclude_from_sim no)
		(in_bom yes)
		(on_board yes)
		(dnp no)
		(fields_autoplaced yes)
		(property "Reference" "U14"
			(at 220.98 41.91 0)
			(effects
				(font
					(size 1.27 1.27)
					(thickness 0.15)
				)
			)
		)
		(property "Value" "EZX710AT2_S_LMR5"
			(at 271.78 54.61 0)
			(effects
				(font
					(size 1.27 1.27)
					(thickness 0.15)
				)
				(justify left bottom)
				(hide yes)
			)
		)
		(property "Footprint" "antmicro-footprints:FCBGA-503_22x22mm_Layout21x24_P1mm"
			(at 271.78 57.15 0)
			(effects
				(font
					(size 1.27 1.27)
					(thickness 0.15)
				)
				(justify left bottom)
				(hide yes)
			)
		)
		(property "Datasheet" "https://www.google.com/url?sa=t&source=web&rct=j&opi=89978449&url=https://cdrdv2-public.intel.com/596333/596333_X710-TM4_Datasheet_v_2_4.pdf&ved=2ahUKEwiSuv20_sCOAxXVCRAIHdxGO_UQFnoECBEQAQ&usg=AOvVaw1CjGyrGWE8ZvOdw4VBsY6U"
			(at 271.78 59.69 0)
			(effects
				(font
					(size 1.27 1.27)
					(thickness 0.15)
				)
				(justify left bottom)
				(hide yes)
			)
		)
		(property "Description" "Ethernet ICs Intel Ethernet Controller 10 Gigabit X7"
			(at 271.78 62.23 0)
			(effects
				(font
					(size 1.27 1.27)
					(thickness 0.15)
				)
				(justify left bottom)
				(hide yes)
			)
		)
		(property "MPN" "EZX710AT2 S LMR5"
			(at 220.98 44.45 0)
			(effects
				(font
					(size 1.27 1.27)
					(thickness 0.15)
				)
			)
		)
		(property "Manufacturer" "Intel"
			(at 271.78 64.77 0)
			(effects
				(font
					(size 1.27 1.27)
					(thickness 0.15)
				)
				(justify left bottom)
				(hide yes)
			)
		)
		(property "Author" "Antmicro"
			(at 271.78 67.31 0)
			(effects
				(font
					(size 1.27 1.27)
					(thickness 0.15)
				)
				(justify left bottom)
				(hide yes)
			)
		)
		(property "License" "Apache-2.0"
			(at 271.78 69.85 0)
			(effects
				(font
					(size 1.27 1.27)
					(thickness 0.15)
				)
				(justify left bottom)
				(hide yes)
			)
		)
		(pin "B26"
		)
		(pin "E7"
		)
		(pin "G9"
		)
		(pin "E5"
		)
		(pin "A17"
		)
		(pin "J15"
		)
		(pin "P34"
		)
		(pin "AD30"
		)
		(pin "J7"
		)
		(pin "C1"
		)
		(pin "G37"
		)
		(pin "N37"
		)
		(pin "F38"
		)
		(pin "B2"
		)
		(pin "N29"
		)
		(pin "D4"
		)
		(pin "Y24"
		)
		(pin "N35"
		)
		(pin "C5"
		)
		(pin "V42"
		)
		(pin "M20"
		)
		(pin "P10"
		)
		(pin "L37"
		)
		(pin "B34"
		)
		(pin "U37"
		)
		(pin "AC7"
		)
		(pin "M4"
		)
		(pin "U35"
		)
		(pin "D18"
		)
		(pin "H16"
		)
		(pin "V30"
		)
		(pin "B38"
		)
		(pin "W29"
		)
		(pin "AB22"
		)
		(pin "AC15"
		)
		(pin "B28"
		)
		(pin "G3"
		)
		(pin "P32"
		)
		(pin "H14"
		)
		(pin "G13"
		)
		(pin "B30"
		)
		(pin "D22"
		)
		(pin "V10"
		)
		(pin "B24"
		)
		(pin "AD4"
		)
		(pin "AC5"
		)
		(pin "AA5"
		)
		(pin "V24"
		)
		(pin "V6"
		)
		(pin "D10"
		)
		(pin "AD20"
		)
		(pin "T26"
		)
		(pin "T10"
		)
		(pin "T12"
		)
		(pin "AD6"
		)
		(pin "H8"
		)
		(pin "H28"
		)
		(pin "N15"
		)
		(pin "AC29"
		)
		(pin "N17"
		)
		(pin "W31"
		)
		(pin "Y12"
		)
		(pin "W23"
		)
		(pin "AD32"
		)
		(pin "AB16"
		)
		(pin "T28"
		)
		(pin "D24"
		)
		(pin "D26"
		)
		(pin "G17"
		)
		(pin "K32"
		)
		(pin "F24"
		)
		(pin "F26"
		)
		(pin "J31"
		)
		(pin "T30"
		)
		(pin "AD34"
		)
		(pin "AA27"
		)
		(pin "R17"
		)
		(pin "W13"
		)
		(pin "M26"
		)
		(pin "C9"
		)
		(pin "AA41"
		)
		(pin "AC27"
		)
		(pin "K2"
		)
		(pin "AB20"
		)
		(pin "R7"
		)
		(pin "N39"
		)
		(pin "D6"
		)
		(pin "M22"
		)
		(pin "M2"
		)
		(pin "AC9"
		)
		(pin "A3"
		)
		(pin "P2"
		)
		(pin "AA33"
		)
		(pin "A23"
		)
		(pin "E35"
		)
		(pin "U3"
		)
		(pin "V36"
		)
		(pin "K42"
		)
		(pin "R41"
		)
		(pin "R1"
		)
		(pin "AD22"
		)
		(pin "W7"
		)
		(pin "AB18"
		)
		(pin "E19"
		)
		(pin "AB12"
		)
		(pin "AD28"
		)
		(pin "AD40"
		)
		(pin "J1"
		)
		(pin "Y6"
		)
		(pin "Y8"
		)
		(pin "H36"
		)
		(pin "C13"
		)
		(pin "C23"
		)
		(pin "Y38"
		)
		(pin "U21"
		)
		(pin "F32"
		)
		(pin "F34"
		)
		(pin "A25"
		)
		(pin "N23"
		)
		(pin "W41"
		)
		(pin "AC31"
		)
		(pin "D12"
		)
		(pin "K34"
		)
		(pin "AA23"
		)
		(pin "AC17"
		)
		(pin "V22"
		)
		(pin "AA39"
		)
		(pin "J41"
		)
		(pin "V14"
		)
		(pin "U23"
		)
		(pin "V16"
		)
		(pin "W35"
		)
		(pin "AC21"
		)
		(pin "D32"
		)
		(pin "L1"
		)
		(pin "P24"
		)
		(pin "J3"
		)
		(pin "AC41"
		)
		(pin "AD14"
		)
		(pin "K22"
		)
		(pin "A11"
		)
		(pin "AA15"
		)
		(pin "F2"
		)
		(pin "A9"
		)
		(pin "N27"
		)
		(pin "C19"
		)
		(pin "K30"
		)
		(pin "L23"
		)
		(pin "N41"
		)
		(pin "F20"
		)
		(pin "AB28"
		)
		(pin "AD12"
		)
		(pin "C21"
		)
		(pin "U9"
		)
		(pin "V20"
		)
		(pin "D20"
		)
		(pin "L21"
		)
		(pin "R15"
		)
		(pin "K4"
		)
		(pin "N1"
		)
		(pin "H12"
		)
		(pin "J23"
		)
		(pin "J5"
		)
		(pin "E9"
		)
		(pin "M28"
		)
		(pin "U1"
		)
		(pin "Y2"
		)
		(pin "G5"
		)
		(pin "K20"
		)
		(pin "M18"
		)
		(pin "V2"
		)
		(pin "AC39"
		)
		(pin "T32"
		)
		(pin "E25"
		)
		(pin "AD38"
		)
		(pin "H26"
		)
		(pin "AA31"
		)
		(pin "G31"
		)
		(pin "U27"
		)
		(pin "U17"
		)
		(pin "C11"
		)
		(pin "N3"
		)
		(pin "A37"
		)
		(pin "F6"
		)
		(pin "Y30"
		)
		(pin "U7"
		)
		(pin "G15"
		)
		(pin "C29"
		)
		(pin "E39"
		)
		(pin "A35"
		)
		(pin "L3"
		)
		(pin "N25"
		)
		(pin "R25"
		)
		(pin "J37"
		)
		(pin "H42"
		)
		(pin "AD24"
		)
		(pin "B14"
		)
		(pin "P6"
		)
		(pin "R31"
		)
		(pin "A5"
		)
		(pin "D14"
		)
		(pin "AB10"
		)
		(pin "B18"
		)
		(pin "A27"
		)
		(pin "T40"
		)
		(pin "AB40"
		)
		(pin "P4"
		)
		(pin "AA35"
		)
		(pin "F36"
		)
		(pin "K18"
		)
		(pin "K38"
		)
		(pin "N33"
		)
		(pin "Y26"
		)
		(pin "Y28"
		)
		(pin "G21"
		)
		(pin "AA1"
		)
		(pin "AB2"
		)
		(pin "V38"
		)
		(pin "J9"
		)
		(pin "B6"
		)
		(pin "L35"
		)
		(pin "N7"
		)
		(pin "AC1"
		)
		(pin "E23"
		)
		(pin "F40"
		)
		(pin "F42"
		)
		(pin "P36"
		)
		(pin "F4"
		)
		(pin "AD16"
		)
		(pin "R11"
		)
		(pin "R27"
		)
		(pin "J13"
		)
		(pin "V34"
		)
		(pin "M10"
		)
		(pin "Y4"
		)
		(pin "Y40"
		)
		(pin "L27"
		)
		(pin "L9"
		)
		(pin "K10"
		)
		(pin "L39"
		)
		(pin "U5"
		)
		(pin "AB42"
		)
		(pin "R5"
		)
		(pin "G23"
		)
		(pin "M8"
		)
		(pin "AD8"
		)
		(pin "M16"
		)
		(pin "M12"
		)
		(pin "E3"
		)
		(pin "B12"
		)
		(pin "R23"
		)
		(pin "W25"
		)
		(pin "H4"
		)
		(pin "F8"
		)
		(pin "AC23"
		)
		(pin "AA3"
		)
		(pin "B10"
		)
		(pin "E31"
		)
		(pin "E33"
		)
		(pin "G1"
		)
		(pin "F18"
		)
		(pin "W17"
		)
		(pin "K36"
		)
		(pin "AB26"
		)
		(pin "R13"
		)
		(pin "AB32"
		)
		(pin "V18"
		)
		(pin "D16"
		)
		(pin "AA37"
		)
		(pin "C31"
		)
		(pin "C41"
		)
		(pin "A41"
		)
		(pin "E1"
		)
		(pin "P38"
		)
		(pin "U19"
		)
		(pin "R29"
		)
		(pin "E37"
		)
		(pin "E29"
		)
		(pin "A21"
		)
		(pin "A31"
		)
		(pin "U29"
		)
		(pin "AB34"
		)
		(pin "E17"
		)
		(pin "W15"
		)
		(pin "H40"
		)
		(pin "M24"
		)
		(pin "U15"
		)
		(pin "H2"
		)
		(pin "N21"
		)
		(pin "W33"
		)
		(pin "J29"
		)
		(pin "T42"
		)
		(pin "A13"
		)
		(pin "AD26"
		)
		(pin "P28"
		)
		(pin "T24"
		)
		(pin "F12"
		)
		(pin "AD2"
		)
		(pin "H34"
		)
		(pin "J33"
		)
		(pin "P40"
		)
		(pin "C17"
		)
		(pin "W19"
		)
		(pin "M6"
		)
		(pin "H6"
		)
		(pin "M40"
		)
		(pin "D30"
		)
		(pin "F10"
		)
		(pin "Y14"
		)
		(pin "L29"
		)
		(pin "P22"
		)
		(pin "W1"
		)
		(pin "V28"
		)
		(pin "E11"
		)
		(pin "J25"
		)
		(pin "G27"
		)
		(pin "M34"
		)
		(pin "Y18"
		)
		(pin "K8"
		)
		(pin "AC35"
		)
		(pin "AD36"
		)
		(pin "G19"
		)
		(pin "G41"
		)
		(pin "W3"
		)
		(pin "C37"
		)
		(pin "C27"
		)
		(pin "Y22"
		)
		(pin "C35"
		)
		(pin "L41"
		)
		(pin "P30"
		)
		(pin "V8"
		)
		(pin "AB30"
		)
		(pin "A29"
		)
		(pin "B22"
		)
		(pin "B32"
		)
		(pin "T36"
		)
		(pin "AA17"
		)
		(pin "K12"
		)
		(pin "P8"
		)
		(pin "T22"
		)
		(pin "C15"
		)
		(pin "W9"
		)
		(pin "W11"
		)
		(pin "P42"
		)
		(pin "T6"
		)
		(pin "B40"
		)
		(pin "N9"
		)
		(pin "K6"
		)
		(pin "A33"
		)
		(pin "T38"
		)
		(pin "J35"
		)
		(pin "E41"
		)
		(pin "T2"
		)
		(pin "C3"
		)
		(pin "R3"
		)
		(pin "D8"
		)
		(pin "F28"
		)
		(pin "F30"
		)
		(pin "Y32"
		)
		(pin "Y36"
		)
		(pin "AC25"
		)
		(pin "T4"
		)
		(pin "V26"
		)
		(pin "B16"
		)
		(pin "V32"
		)
		(pin "H10"
		)
		(pin "A7"
		)
		(pin "R9"
		)
		(pin "N11"
		)
		(pin "R37"
		)
		(pin "W37"
		)
		(pin "V4"
		)
		(pin "T14"
		)
		(pin "T16"
		)
		(pin "J21"
		)
		(pin "AB14"
		)
		(pin "J17"
		)
		(pin "W5"
		)
		(pin "D34"
		)
		(pin "Y34"
		)
		(pin "M36"
		)
		(pin "AA25"
		)
		(pin "B4"
		)
		(pin "AA29"
		)
		(pin "K16"
		)
		(pin "V40"
		)
		(pin "AC37"
		)
		(pin "AB24"
		)
		(pin "AD18"
		)
		(pin "AA7"
		)
		(pin "V12"
		)
		(pin "AC13"
		)
		(pin "T8"
		)
		(pin "E21"
		)
		(pin "A19"
		)
		(pin "E27"
		)
		(pin "K14"
		)
		(pin "AA13"
		)
		(pin "P16"
		)
		(pin "P18"
		)
		(pin "H30"
		)
		(pin "N31"
		)
		(pin "P12"
		)
		(pin "P14"
		)
		(pin "B42"
		)
		(pin "G25"
		)
		(pin "U25"
		)
		(pin "A39"
		)
		(pin "J11"
		)
		(pin "G11"
		)
		(pin "G29"
		)
		(pin "R19"
		)
		(pin "AC11"
		)
		(pin "F22"
		)
		(pin "W39"
		)
		(pin "AA9"
		)
		(pin "AB38"
		)
		(pin "L31"
		)
		(pin "T34"
		)
		(pin "J39"
		)
		(pin "F14"
		)
		(pin "H24"
		)
		(pin "G35"
		)
		(pin "W21"
		)
		(pin "K40"
		)
		(pin "N19"
		)
		(pin "B20"
		)
		(pin "U31"
		)
		(pin "R21"
		)
		(pin "R39"
		)
		(pin "P20"
		)
		(pin "R35"
		)
		(pin "AD42"
		)
		(pin "K24"
		)
		(pin "AB4"
		)
		(pin "AC33"
		)
		(pin "B8"
		)
		(pin "U33"
		)
		(pin "H32"
		)
		(pin "L33"
		)
		(pin "J19"
		)
		(pin "U13"
		)
		(pin "C39"
		)
		(pin "H22"
		)
		(pin "AD10"
		)
		(pin "Y20"
		)
		(pin "E15"
		)
		(pin "AA21"
		)
		(pin "K26"
		)
		(pin "C25"
		)
		(pin "M42"
		)
		(pin "U41"
		)
		(pin "Y16"
		)
		(pin "D28"
		)
		(pin "D36"
		)
		(pin "Y10"
		)
		(pin "AC19"
		)
		(pin "AB8"
		)
		(pin "AB36"
		)
		(pin "P26"
		)
		(pin "D38"
		)
		(pin "D40"
		)
		(pin "AA19"
		)
		(pin "E13"
		)
		(pin "A15"
		)
		(pin "H20"
		)
		(pin "K28"
		)
		(pin "F16"
		)
		(pin "W27"
		)
		(pin "D42"
		)
		(pin "AB6"
		)
		(pin "M14"
		)
		(pin "M32"
		)
		(pin "N5"
		)
		(pin "U11"
		)
		(pin "J27"
		)
		(pin "M30"
		)
		(pin "C33"
		)
		(pin "C7"
		)
		(pin "L15"
		)
		(pin "G33"
		)
		(pin "L19"
		)
		(pin "L17"
		)
		(pin "L5"
		)
		(pin "L25"
		)
		(pin "M38"
		)
		(pin "T18"
		)
		(pin "T20"
		)
		(pin "H18"
		)
		(pin "G7"
		)
		(pin "B36"
		)
		(pin "U39"
		)
		(pin "G39"
		)
		(pin "D2"
		)
		(pin "R33"
		)
		(pin "L11"
		)
		(pin "AC3"
		)
		(pin "AA11"
		)
		(pin "H38"
		)
		(pin "N13"
		)
		(pin "L13"
		)
		(pin "L7"
		)
		(pin "Y42"
		)
		(instances
			(project ""
				(path ""
					(reference "U9")
					(unit 5)
				)
			)
			(project "thunderbolt-to-10gbe-adapter"
				(path ""
					(reference "U14")
					(unit 5)
				)
			)
		)
	)
	(symbol
		(lib_id "antmicropower:+1V8")
		(at 173.99 166.37 0)
		(unit 1)
		(exclude_from_sim no)
		(in_bom yes)
		(on_board yes)
		(dnp no)
		(property "Reference" "#PWR0364"
			(at 189.23 168.91 0)
			(effects
				(font
					(size 1.27 1.27)
					(thickness 0.15)
				)
				(justify left bottom)
				(hide yes)
			)
		)
		(property "Value" "+1V88"
			(at 173.99 162.56 0)
			(effects
				(font
					(size 1.27 1.27)
					(thickness 0.15)
				)
			)
		)
		(property "Footprint" ""
			(at 189.23 173.99 0)
			(effects
				(font
					(size 1.27 1.27)
					(thickness 0.15)
				)
				(justify left bottom)
				(hide yes)
			)
		)
		(property "Datasheet" ""
			(at 189.23 176.53 0)
			(effects
				(font
					(size 1.27 1.27)
					(thickness 0.15)
				)
				(justify left bottom)
				(hide yes)
			)
		)
		(property "Description" ""
			(at 173.99 166.37 0)
			(effects
				(font
					(size 1.27 1.27)
				)
				(hide yes)
			)
		)
		(property "Author" "Antmicro"
			(at 189.23 171.45 0)
			(effects
				(font
					(size 1.27 1.27)
					(thickness 0.15)
				)
				(justify left bottom)
				(hide yes)
			)
		)
		(property "License" "Apache-2.0"
			(at 189.23 173.99 0)
			(effects
				(font
					(size 1.27 1.27)
					(thickness 0.15)
				)
				(justify left bottom)
				(hide yes)
			)
		)
		(pin "1"
		)
		(instances
			(project "OCuLink to 10GbE adapter"
				(path ""
					(reference "#PWR0301")
					(unit 1)
				)
			)
			(project "thunderbolt-to-10gbe-adapter"
				(path ""
					(reference "#PWR0364")
					(unit 1)
				)
			)
		)
	)
	(symbol
		(lib_id "antmicropower:GND")
		(at 171.45 83.82 0)
		(unit 1)
		(exclude_from_sim no)
		(in_bom yes)
		(on_board yes)
		(dnp no)
		(property "Reference" "#PWR0363"
			(at 180.34 86.36 0)
			(effects
				(font
					(size 1.27 1.27)
					(thickness 0.15)
				)
				(justify left bottom)
				(hide yes)
			)
		)
		(property "Value" "GND"
			(at 171.45 87.63 0)
			(effects
				(font
					(size 1.27 1.27)
					(thickness 0.15)
				)
			)
		)
		(property "Footprint" ""
			(at 180.34 91.44 0)
			(effects
				(font
					(size 1.27 1.27)
					(thickness 0.15)
				)
				(justify left bottom)
				(hide yes)
			)
		)
		(property "Datasheet" ""
			(at 180.34 96.52 0)
			(effects
				(font
					(size 1.27 1.27)
					(thickness 0.15)
				)
				(justify left bottom)
				(hide yes)
			)
		)
		(property "Description" ""
			(at 171.45 83.82 0)
			(effects
				(font
					(size 1.27 1.27)
				)
				(hide yes)
			)
		)
		(property "Author" "Antmicro"
			(at 180.34 91.44 0)
			(effects
				(font
					(size 1.27 1.27)
					(thickness 0.15)
				)
				(justify left bottom)
				(hide yes)
			)
		)
		(property "License" "Apache-2.0"
			(at 180.34 93.98 0)
			(effects
				(font
					(size 1.27 1.27)
					(thickness 0.15)
				)
				(justify left bottom)
				(hide yes)
			)
		)
		(pin "1"
		)
		(instances
			(project "OCuLink to 10GbE adapter"
				(path ""
					(reference "#PWR0299")
					(unit 1)
				)
			)
			(project "thunderbolt-to-10gbe-adapter"
				(path ""
					(reference "#PWR0363")
					(unit 1)
				)
			)
		)
	)
	(symbol
		(lib_id "antmicroResistors0402:R_100R_0402")
		(at 135.89 81.28 90)
		(unit 1)
		(exclude_from_sim no)
		(in_bom yes)
		(on_board yes)
		(dnp no)
		(property "Reference" "R123"
			(at 137.414 77.47 90)
			(effects
				(font
					(size 1.27 1.27)
					(thickness 0.15)
				)
				(justify right)
			)
		)
		(property "Value" "R_100R_0402"
			(at 148.59 60.96 0)
			(effects
				(font
					(size 1.27 1.27)
					(thickness 0.15)
				)
				(justify left bottom)
				(hide yes)
			)
		)
		(property "Footprint" "antmicro-footprints:R_0402_1005Metric"
			(at 151.13 60.96 0)
			(effects
				(font
					(size 1.27 1.27)
					(thickness 0.15)
				)
				(justify left bottom)
				(hide yes)
			)
		)
		(property "Datasheet" "https://www.bourns.com/docs/product-datasheets/cr.pdf"
			(at 153.67 60.96 0)
			(effects
				(font
					(size 1.27 1.27)
					(thickness 0.15)
				)
				(justify left bottom)
				(hide yes)
			)
		)
		(property "Description" "SMD Chip Resistor, 100 ohm, ± 1%, 62.5 mW, 0402 [1005 Metric], Thick Film, General Purpose"
			(at 135.89 81.28 0)
			(effects
				(font
					(size 1.27 1.27)
				)
				(hide yes)
			)
		)
		(property "MPN" "CR0402-FX-1000GLF"
			(at 156.21 60.96 0)
			(effects
				(font
					(size 1.27 1.27)
					(thickness 0.15)
				)
				(justify left bottom)
				(hide yes)
			)
		)
		(property "Manufacturer" "Bourns"
			(at 158.75 60.96 0)
			(effects
				(font
					(size 1.27 1.27)
					(thickness 0.15)
				)
				(justify left bottom)
				(hide yes)
			)
		)
		(property "License" "Apache-2.0"
			(at 161.29 60.96 0)
			(effects
				(font
					(size 1.27 1.27)
					(thickness 0.15)
				)
				(justify left bottom)
				(hide yes)
			)
		)
		(property "Author" "Antmicro"
			(at 163.83 60.96 0)
			(effects
				(font
					(size 1.27 1.27)
					(thickness 0.15)
				)
				(justify left bottom)
				(hide yes)
			)
		)
		(property "Val" "100R"
			(at 137.414 80.01 90)
			(effects
				(font
					(size 1.27 1.27)
					(thickness 0.15)
				)
				(justify right)
			)
		)
		(property "Tolerance" "1%"
			(at 146.05 60.96 0)
			(effects
				(font
					(size 1.27 1.27)
				)
				(justify left bottom)
				(hide yes)
			)
		)
		(pin "2"
		)
		(pin "1"
		)
		(instances
			(project "OCuLink to 10GbE adapter"
				(path ""
					(reference "R136")
					(unit 1)
				)
			)
			(project "thunderbolt-to-10gbe-adapter"
				(path ""
					(reference "R123")
					(unit 1)
				)
			)
		)
	)
	(symbol
		(lib_id "antmicroResistors0402:R_10k_0402")
		(at 269.24 62.23 90)
		(unit 1)
		(exclude_from_sim no)
		(in_bom yes)
		(on_board yes)
		(dnp no)
		(property "Reference" "R134"
			(at 270.764 58.42 90)
			(effects
				(font
					(size 1.27 1.27)
					(thickness 0.15)
				)
				(justify right)
			)
		)
		(property "Value" "R_10k_0402"
			(at 281.94 41.91 0)
			(effects
				(font
					(size 1.27 1.27)
					(thickness 0.15)
				)
				(justify left bottom)
				(hide yes)
			)
		)
		(property "Footprint" "antmicro-footprints:R_0402_1005Metric"
			(at 284.48 41.91 0)
			(effects
				(font
					(size 1.27 1.27)
					(thickness 0.15)
				)
				(justify left bottom)
				(hide yes)
			)
		)
		(property "Datasheet" "https://www.bourns.com/docs/product-datasheets/cr.pdf"
			(at 287.02 41.91 0)
			(effects
				(font
					(size 1.27 1.27)
					(thickness 0.15)
				)
				(justify left bottom)
				(hide yes)
			)
		)
		(property "Description" "SMD Chip Resistor, 10 kohm, ± 1%, 62.5 mW, 0402 [1005 Metric], Thick Film, General Purpose"
			(at 269.24 62.23 0)
			(effects
				(font
					(size 1.27 1.27)
				)
				(hide yes)
			)
		)
		(property "MPN" "CR0402-FX-1002GLF"
			(at 289.56 41.91 0)
			(effects
				(font
					(size 1.27 1.27)
					(thickness 0.15)
				)
				(justify left bottom)
				(hide yes)
			)
		)
		(property "Manufacturer" "Bourns"
			(at 292.1 41.91 0)
			(effects
				(font
					(size 1.27 1.27)
					(thickness 0.15)
				)
				(justify left bottom)
				(hide yes)
			)
		)
		(property "License" "Apache-2.0"
			(at 294.64 41.91 0)
			(effects
				(font
					(size 1.27 1.27)
					(thickness 0.15)
				)
				(justify left bottom)
				(hide yes)
			)
		)
		(property "Author" "Antmicro"
			(at 297.18 41.91 0)
			(effects
				(font
					(size 1.27 1.27)
					(thickness 0.15)
				)
				(justify left bottom)
				(hide yes)
			)
		)
		(property "Val" "10k"
			(at 270.764 60.96 90)
			(effects
				(font
					(size 1.27 1.27)
					(thickness 0.15)
				)
				(justify right)
			)
		)
		(property "Tolerance" "1%"
			(at 279.4 41.91 0)
			(effects
				(font
					(size 1.27 1.27)
				)
				(justify left bottom)
				(hide yes)
			)
		)
		(pin "1"
		)
		(pin "2"
		)
		(instances
			(project "OCuLink to 10GbE adapter"
				(path ""
					(reference "R132")
					(unit 1)
				)
			)
			(project "thunderbolt-to-10gbe-adapter"
				(path ""
					(reference "R134")
					(unit 1)
				)
			)
		)
	)
	(symbol
		(lib_id "antmicroResistors0402:R_100R_0402")
		(at 153.67 81.28 90)
		(unit 1)
		(exclude_from_sim no)
		(in_bom yes)
		(on_board yes)
		(dnp no)
		(property "Reference" "R125"
			(at 155.194 77.47 90)
			(effects
				(font
					(size 1.27 1.27)
					(thickness 0.15)
				)
				(justify right)
			)
		)
		(property "Value" "R_100R_0402"
			(at 166.37 60.96 0)
			(effects
				(font
					(size 1.27 1.27)
					(thickness 0.15)
				)
				(justify left bottom)
				(hide yes)
			)
		)
		(property "Footprint" "antmicro-footprints:R_0402_1005Metric"
			(at 168.91 60.96 0)
			(effects
				(font
					(size 1.27 1.27)
					(thickness 0.15)
				)
				(justify left bottom)
				(hide yes)
			)
		)
		(property "Datasheet" "https://www.bourns.com/docs/product-datasheets/cr.pdf"
			(at 171.45 60.96 0)
			(effects
				(font
					(size 1.27 1.27)
					(thickness 0.15)
				)
				(justify left bottom)
				(hide yes)
			)
		)
		(property "Description" "SMD Chip Resistor, 100 ohm, ± 1%, 62.5 mW, 0402 [1005 Metric], Thick Film, General Purpose"
			(at 153.67 81.28 0)
			(effects
				(font
					(size 1.27 1.27)
				)
				(hide yes)
			)
		)
		(property "MPN" "CR0402-FX-1000GLF"
			(at 173.99 60.96 0)
			(effects
				(font
					(size 1.27 1.27)
					(thickness 0.15)
				)
				(justify left bottom)
				(hide yes)
			)
		)
		(property "Manufacturer" "Bourns"
			(at 176.53 60.96 0)
			(effects
				(font
					(size 1.27 1.27)
					(thickness 0.15)
				)
				(justify left bottom)
				(hide yes)
			)
		)
		(property "License" "Apache-2.0"
			(at 179.07 60.96 0)
			(effects
				(font
					(size 1.27 1.27)
					(thickness 0.15)
				)
				(justify left bottom)
				(hide yes)
			)
		)
		(property "Author" "Antmicro"
			(at 181.61 60.96 0)
			(effects
				(font
					(size 1.27 1.27)
					(thickness 0.15)
				)
				(justify left bottom)
				(hide yes)
			)
		)
		(property "Val" "100R"
			(at 155.194 80.01 90)
			(effects
				(font
					(size 1.27 1.27)
					(thickness 0.15)
				)
				(justify right)
			)
		)
		(property "Tolerance" "1%"
			(at 163.83 60.96 0)
			(effects
				(font
					(size 1.27 1.27)
				)
				(justify left bottom)
				(hide yes)
			)
		)
		(pin "2"
		)
		(pin "1"
		)
		(instances
			(project "OCuLink to 10GbE adapter"
				(path ""
					(reference "R138")
					(unit 1)
				)
			)
			(project "thunderbolt-to-10gbe-adapter"
				(path ""
					(reference "R125")
					(unit 1)
				)
			)
		)
	)
	(symbol
		(lib_id "antmicropower:+3V3")
		(at 276.86 21.59 0)
		(unit 1)
		(exclude_from_sim no)
		(in_bom yes)
		(on_board yes)
		(dnp no)
		(property "Reference" "#PWR0370"
			(at 292.1 21.59 0)
			(effects
				(font
					(size 1.27 1.27)
					(thickness 0.15)
				)
				(justify left bottom)
				(hide yes)
			)
		)
		(property "Value" "+3V3"
			(at 276.86 17.78 0)
			(effects
				(font
					(size 1.27 1.27)
					(thickness 0.15)
				)
			)
		)
		(property "Footprint" ""
			(at 292.1 29.21 0)
			(effects
				(font
					(size 1.27 1.27)
					(thickness 0.15)
				)
				(justify left bottom)
				(hide yes)
			)
		)
		(property "Datasheet" ""
			(at 292.1 31.75 0)
			(effects
				(font
					(size 1.27 1.27)
					(thickness 0.15)
				)
				(justify left bottom)
				(hide yes)
			)
		)
		(property "Description" ""
			(at 276.86 21.59 0)
			(effects
				(font
					(size 1.27 1.27)
				)
				(hide yes)
			)
		)
		(property "Author" "Antmicro"
			(at 292.1 24.13 0)
			(effects
				(font
					(size 1.27 1.27)
					(thickness 0.15)
				)
				(justify left bottom)
				(hide yes)
			)
		)
		(property "License" "Apache-2.0"
			(at 292.1 26.67 0)
			(effects
				(font
					(size 1.27 1.27)
					(thickness 0.15)
				)
				(justify left bottom)
				(hide yes)
			)
		)
		(pin "1"
		)
		(instances
			(project "OCuLink to 10GbE adapter"
				(path ""
					(reference "#PWR0289")
					(unit 1)
				)
			)
			(project "thunderbolt-to-10gbe-adapter"
				(path ""
					(reference "#PWR0370")
					(unit 1)
				)
			)
		)
	)
	(symbol
		(lib_id "antmicroSlideSwitches:SW_DS04-254-1-01BK-SMT")
		(at 276.86 36.83 90)
		(unit 1)
		(exclude_from_sim no)
		(in_bom yes)
		(on_board yes)
		(dnp yes)
		(fields_autoplaced yes)
		(property "Reference" "SW1"
			(at 280.67 29.21 90)
			(effects
				(font
					(size 1.27 1.27)
					(thickness 0.15)
				)
				(justify right)
			)
		)
		(property "Value" "SW_DS04-254-1-01BK-SMT"
			(at 280.67 31.75 90)
			(effects
				(font
					(size 1.27 1.27)
					(thickness 0.15)
				)
				(justify right)
				(hide yes)
			)
		)
		(property "Footprint" "antmicro-footprints:SW_DS04-254-1-01BK-SMT"
			(at 284.48 10.16 0)
			(effects
				(font
					(size 1.27 1.27)
					(thickness 0.15)
				)
				(justify left bottom)
				(hide yes)
			)
		)
		(property "Datasheet" "https://www.mouser.com/datasheet/2/670/ds04_254_smt-1777718.pdf"
			(at 287.02 10.16 0)
			(effects
				(font
					(size 1.27 1.27)
					(thickness 0.15)
				)
				(justify left bottom)
				(hide yes)
			)
		)
		(property "Description" "Slide switch"
			(at 299.72 10.16 0)
			(effects
				(font
					(size 1.27 1.27)
				)
				(justify left bottom)
				(hide yes)
			)
		)
		(property "MPN" "DS04-254-1-01BK-SMT"
			(at 280.67 31.75 90)
			(effects
				(font
					(size 1.27 1.27)
					(thickness 0.15)
				)
				(justify right)
			)
		)
		(property "Manufacturer" "CUI Inc"
			(at 292.1 10.16 0)
			(effects
				(font
					(size 1.27 1.27)
					(thickness 0.15)
				)
				(justify left bottom)
				(hide yes)
			)
		)
		(property "Author" "Antmicro"
			(at 294.64 10.16 0)
			(effects
				(font
					(size 1.27 1.27)
					(thickness 0.15)
				)
				(justify left bottom)
				(hide yes)
			)
		)
		(property "License" "Apache-2.0"
			(at 297.18 10.16 0)
			(effects
				(font
					(size 1.27 1.27)
					(thickness 0.15)
				)
				(justify left bottom)
				(hide yes)
			)
		)
		(pin "2"
		)
		(pin "1"
		)
		(instances
			(project "oculink-to-10gbe-adapter"
				(path ""
					(reference "SW1")
					(unit 1)
				)
			)
			(project "thunderbolt-to-10gbe-adapter"
				(path ""
					(reference "SW1")
					(unit 1)
				)
			)
		)
	)
	(symbol
		(lib_id "antmicropower:GND")
		(at 144.78 83.82 0)
		(unit 1)
		(exclude_from_sim no)
		(in_bom yes)
		(on_board yes)
		(dnp no)
		(property "Reference" "#PWR0360"
			(at 153.67 86.36 0)
			(effects
				(font
					(size 1.27 1.27)
					(thickness 0.15)
				)
				(justify left bottom)
				(hide yes)
			)
		)
		(property "Value" "GND"
			(at 144.78 87.63 0)
			(effects
				(font
					(size 1.27 1.27)
					(thickness 0.15)
				)
			)
		)
		(property "Footprint" ""
			(at 153.67 91.44 0)
			(effects
				(font
					(size 1.27 1.27)
					(thickness 0.15)
				)
				(justify left bottom)
				(hide yes)
			)
		)
		(property "Datasheet" ""
			(at 153.67 96.52 0)
			(effects
				(font
					(size 1.27 1.27)
					(thickness 0.15)
				)
				(justify left bottom)
				(hide yes)
			)
		)
		(property "Description" ""
			(at 144.78 83.82 0)
			(effects
				(font
					(size 1.27 1.27)
				)
				(hide yes)
			)
		)
		(property "Author" "Antmicro"
			(at 153.67 91.44 0)
			(effects
				(font
					(size 1.27 1.27)
					(thickness 0.15)
				)
				(justify left bottom)
				(hide yes)
			)
		)
		(property "License" "Apache-2.0"
			(at 153.67 93.98 0)
			(effects
				(font
					(size 1.27 1.27)
					(thickness 0.15)
				)
				(justify left bottom)
				(hide yes)
			)
		)
		(pin "1"
		)
		(instances
			(project "OCuLink to 10GbE adapter"
				(path ""
					(reference "#PWR0296")
					(unit 1)
				)
			)
			(project "thunderbolt-to-10gbe-adapter"
				(path ""
					(reference "#PWR0360")
					(unit 1)
				)
			)
		)
	)
	(symbol
		(lib_id "antmicropower:GND")
		(at 193.04 250.19 0)
		(unit 1)
		(exclude_from_sim no)
		(in_bom yes)
		(on_board yes)
		(dnp no)
		(property "Reference" "#PWR0366"
			(at 201.93 252.73 0)
			(effects
				(font
					(size 1.27 1.27)
					(thickness 0.15)
				)
				(justify left bottom)
				(hide yes)
			)
		)
		(property "Value" "GND"
			(at 193.04 254 0)
			(effects
				(font
					(size 1.27 1.27)
					(thickness 0.15)
				)
			)
		)
		(property "Footprint" ""
			(at 201.93 257.81 0)
			(effects
				(font
					(size 1.27 1.27)
					(thickness 0.15)
				)
				(justify left bottom)
				(hide yes)
			)
		)
		(property "Datasheet" ""
			(at 201.93 262.89 0)
			(effects
				(font
					(size 1.27 1.27)
					(thickness 0.15)
				)
				(justify left bottom)
				(hide yes)
			)
		)
		(property "Description" ""
			(at 193.04 250.19 0)
			(effects
				(font
					(size 1.27 1.27)
				)
				(hide yes)
			)
		)
		(property "Author" "Antmicro"
			(at 201.93 257.81 0)
			(effects
				(font
					(size 1.27 1.27)
					(thickness 0.15)
				)
				(justify left bottom)
				(hide yes)
			)
		)
		(property "License" "Apache-2.0"
			(at 201.93 260.35 0)
			(effects
				(font
					(size 1.27 1.27)
					(thickness 0.15)
				)
				(justify left bottom)
				(hide yes)
			)
		)
		(pin "1"
		)
		(instances
			(project "OCuLink to 10GbE adapter"
				(path ""
					(reference "#PWR0316")
					(unit 1)
				)
			)
			(project "thunderbolt-to-10gbe-adapter"
				(path ""
					(reference "#PWR0366")
					(unit 1)
				)
			)
		)
	)
	(symbol
		(lib_id "antmicroResistors0402:R_1k_0402")
		(at 276.86 46.99 90)
		(unit 1)
		(exclude_from_sim no)
		(in_bom yes)
		(on_board yes)
		(dnp no)
		(property "Reference" "R135"
			(at 278.384 43.18 90)
			(effects
				(font
					(size 1.27 1.27)
					(thickness 0.15)
				)
				(justify right)
			)
		)
		(property "Value" "R_1k_0402"
			(at 289.56 26.67 0)
			(effects
				(font
					(size 1.27 1.27)
					(thickness 0.15)
				)
				(justify left bottom)
				(hide yes)
			)
		)
		(property "Footprint" "antmicro-footprints:R_0402_1005Metric"
			(at 292.1 26.67 0)
			(effects
				(font
					(size 1.27 1.27)
					(thickness 0.15)
				)
				(justify left bottom)
				(hide yes)
			)
		)
		(property "Datasheet" "https://www.bourns.com/docs/product-datasheets/cr.pdf"
			(at 294.64 26.67 0)
			(effects
				(font
					(size 1.27 1.27)
					(thickness 0.15)
				)
				(justify left bottom)
				(hide yes)
			)
		)
		(property "Description" "SMD Chip Resistor, 1 kohm, ± 1%, 63 mW, 0402 [1005 Metric], Thick Film, General Purpose"
			(at 276.86 46.99 0)
			(effects
				(font
					(size 1.27 1.27)
				)
				(hide yes)
			)
		)
		(property "MPN" "CR0402-FX-1001GLF"
			(at 297.18 26.67 0)
			(effects
				(font
					(size 1.27 1.27)
					(thickness 0.15)
				)
				(justify left bottom)
				(hide yes)
			)
		)
		(property "Manufacturer" "Bourns"
			(at 299.72 26.67 0)
			(effects
				(font
					(size 1.27 1.27)
					(thickness 0.15)
				)
				(justify left bottom)
				(hide yes)
			)
		)
		(property "License" "Apache-2.0"
			(at 302.26 26.67 0)
			(effects
				(font
					(size 1.27 1.27)
					(thickness 0.15)
				)
				(justify left bottom)
				(hide yes)
			)
		)
		(property "Author" "Antmicro"
			(at 304.8 26.67 0)
			(effects
				(font
					(size 1.27 1.27)
					(thickness 0.15)
				)
				(justify left bottom)
				(hide yes)
			)
		)
		(property "Val" "1k"
			(at 278.384 45.72 90)
			(effects
				(font
					(size 1.27 1.27)
					(thickness 0.15)
				)
				(justify right)
			)
		)
		(property "Tolerance" "1%"
			(at 287.02 26.67 0)
			(effects
				(font
					(size 1.27 1.27)
				)
				(justify left bottom)
				(hide yes)
			)
		)
		(pin "2"
		)
		(pin "1"
		)
		(instances
			(project "OCuLink to 10GbE adapter"
				(path ""
					(reference "R130")
					(unit 1)
				)
			)
			(project "thunderbolt-to-10gbe-adapter"
				(path ""
					(reference "R135")
					(unit 1)
				)
			)
		)
	)
)
